FILE_TYPE = MACRO_DRAWING;
SET COLOR_WIRE YELLOW;
SET COLOR_PROP MONO;
SET COLOR_DOT WHITE;
SET COLOR_ARC YELLOW;
SET COLOR_BODY GREEN;
SET COLOR_NOTE MONO;
SET PROP_DISPLAY VALUE;
SET PAGE_NUMBER P81;
FORCEADD OFFPAGE..3
(1550 5150);
FORCEPROP 2 LAST $XR1 82 
J 0
(1854 5150);
DISPLAY 0.638298 (1854 5150);
PAINT MONO (1854 5150);
FORCEPROP 2 LAST $XR0 59 
J 0
(1764 5150);
DISPLAY 0.638298 (1764 5150);
PAINT MONO (1764 5150);
FORCEPROP 2 LAST CDS_LIB mstr_standard
J 0
(1550 5150);
DISPLAY 0.787234 (1550 5150);
PAINT MONO (1550 5150);
DISPLAY INVISIBLE (1550 5150);
FORCEPROP 1 LAST OFFPAGE TRUE
J 0
(1875 5025);
DISPLAY 0.936170 (1875 5025);
PAINT GREEN (1875 5025);
DISPLAY INVISIBLE (1875 5025);
FORCEPROP 1 LAST COMMENT_BODY TRUE
J 0
(1500 5050);
DISPLAY 0.936170 (1500 5050);
PAINT GREEN (1500 5050);
DISPLAY INVISIBLE (1500 5050);
FORCEPROP 2 LAST PATH I1
J 0
(1750 5225);
DISPLAY 0.787234 (1750 5225);
PAINT MONO (1750 5225);
DISPLAY INVISIBLE (1750 5225);
FORCEADD TAP..6
R 2
(850 4700);
FORCEPROP 3 LASTPIN (800 4700) SIG_NAME M_J_DQS_DN<13>
J 0
(810 4710);
DISPLAY 0.659574 (810 4710);
PAINT MONO (810 4710);
DISPLAY INVISIBLE (810 4710);
FORCEPROP 1 LASTPIN (800 4700) BN 13
J 2
(850 4710);
DISPLAY 0.617021 (850 4710);
PAINT PINK (850 4710);
FORCEPROP 2 LAST CDS_LIB mstr_standard
J 0
(850 4700);
DISPLAY 0.787234 (850 4700);
PAINT MONO (850 4700);
DISPLAY INVISIBLE (850 4700);
FORCEPROP 1 LAST BODY_TYPE PLUMBING
J 2
(850 4650);
DISPLAY 1.234043 (850 4650);
PAINT GREEN (850 4650);
DISPLAY INVISIBLE (850 4650);
FORCEPROP 1 LAST HDL_TAP TRUE
J 2
(525 4575);
DISPLAY 1.234043 (525 4575);
PAINT GREEN (525 4575);
DISPLAY INVISIBLE (525 4575);
FORCEPROP 1 LAST PATH I10
J 2
(850 4700);
DISPLAY 0.936170 (850 4700);
PAINT GREEN (850 4700);
DISPLAY INVISIBLE (850 4700);
FORCEADD TAP..6
R 2
(-1800 2150);
FORCEPROP 3 LASTPIN (-1850 2150) SIG_NAME M_J_DQ<11>
J 0
(-1840 2160);
DISPLAY 0.659574 (-1840 2160);
PAINT MONO (-1840 2160);
DISPLAY INVISIBLE (-1840 2160);
FORCEPROP 1 LASTPIN (-1850 2150) BN 11
J 2
(-1800 2160);
DISPLAY 0.617021 (-1800 2160);
PAINT PINK (-1800 2160);
FORCEPROP 2 LAST CDS_LIB mstr_standard
J 2
(-1800 2150);
DISPLAY 0.787234 (-1800 2150);
PAINT MONO (-1800 2150);
DISPLAY INVISIBLE (-1800 2150);
FORCEPROP 1 LAST BODY_TYPE PLUMBING
J 2
(-1800 2100);
DISPLAY 1.234043 (-1800 2100);
PAINT GREEN (-1800 2100);
DISPLAY INVISIBLE (-1800 2100);
FORCEPROP 1 LAST HDL_TAP TRUE
J 2
(-2125 2025);
DISPLAY 1.234043 (-2125 2025);
PAINT GREEN (-2125 2025);
DISPLAY INVISIBLE (-2125 2025);
FORCEPROP 1 LAST PATH I100
J 2
(-1800 2150);
DISPLAY 0.936170 (-1800 2150);
PAINT GREEN (-1800 2150);
DISPLAY INVISIBLE (-1800 2150);
FORCEADD TAP..6
R 2
(-1800 2100);
FORCEPROP 3 LASTPIN (-1850 2100) SIG_NAME M_J_DQ<8>
J 0
(-1840 2110);
DISPLAY 0.659574 (-1840 2110);
PAINT MONO (-1840 2110);
DISPLAY INVISIBLE (-1840 2110);
FORCEPROP 1 LASTPIN (-1850 2100) BN 8
J 2
(-1800 2110);
DISPLAY 0.617021 (-1800 2110);
PAINT PINK (-1800 2110);
FORCEPROP 2 LAST CDS_LIB mstr_standard
J 2
(-1800 2100);
DISPLAY 0.787234 (-1800 2100);
PAINT MONO (-1800 2100);
DISPLAY INVISIBLE (-1800 2100);
FORCEPROP 1 LAST BODY_TYPE PLUMBING
J 2
(-1800 2050);
DISPLAY 1.234043 (-1800 2050);
PAINT GREEN (-1800 2050);
DISPLAY INVISIBLE (-1800 2050);
FORCEPROP 1 LAST HDL_TAP TRUE
J 2
(-2125 1975);
DISPLAY 1.234043 (-2125 1975);
PAINT GREEN (-2125 1975);
DISPLAY INVISIBLE (-2125 1975);
FORCEPROP 1 LAST PATH I101
J 2
(-1800 2100);
DISPLAY 0.936170 (-1800 2100);
PAINT GREEN (-1800 2100);
DISPLAY INVISIBLE (-1800 2100);
FORCEADD TAP..6
R 2
(-1800 2050);
FORCEPROP 3 LASTPIN (-1850 2050) SIG_NAME M_J_DQ<9>
J 0
(-1840 2060);
DISPLAY 0.659574 (-1840 2060);
PAINT MONO (-1840 2060);
DISPLAY INVISIBLE (-1840 2060);
FORCEPROP 1 LASTPIN (-1850 2050) BN 9
J 2
(-1800 2060);
DISPLAY 0.617021 (-1800 2060);
PAINT PINK (-1800 2060);
FORCEPROP 2 LAST CDS_LIB mstr_standard
J 2
(-1800 2050);
DISPLAY 0.787234 (-1800 2050);
PAINT MONO (-1800 2050);
DISPLAY INVISIBLE (-1800 2050);
FORCEPROP 1 LAST BODY_TYPE PLUMBING
J 2
(-1800 2000);
DISPLAY 1.234043 (-1800 2000);
PAINT GREEN (-1800 2000);
DISPLAY INVISIBLE (-1800 2000);
FORCEPROP 1 LAST HDL_TAP TRUE
J 2
(-2125 1925);
DISPLAY 1.234043 (-2125 1925);
PAINT GREEN (-2125 1925);
DISPLAY INVISIBLE (-2125 1925);
FORCEPROP 1 LAST PATH I102
J 2
(-1800 2050);
DISPLAY 0.936170 (-1800 2050);
PAINT GREEN (-1800 2050);
DISPLAY INVISIBLE (-1800 2050);
FORCEADD TAP..6
R 2
(-1800 2000);
FORCEPROP 3 LASTPIN (-1850 2000) SIG_NAME M_J_DQ<6>
J 0
(-1840 2010);
DISPLAY 0.659574 (-1840 2010);
PAINT MONO (-1840 2010);
DISPLAY INVISIBLE (-1840 2010);
FORCEPROP 1 LASTPIN (-1850 2000) BN 6
J 2
(-1800 2010);
DISPLAY 0.617021 (-1800 2010);
PAINT PINK (-1800 2010);
FORCEPROP 2 LAST CDS_LIB mstr_standard
J 2
(-1800 2000);
DISPLAY 0.787234 (-1800 2000);
PAINT MONO (-1800 2000);
DISPLAY INVISIBLE (-1800 2000);
FORCEPROP 1 LAST BODY_TYPE PLUMBING
J 2
(-1800 1950);
DISPLAY 1.234043 (-1800 1950);
PAINT GREEN (-1800 1950);
DISPLAY INVISIBLE (-1800 1950);
FORCEPROP 1 LAST HDL_TAP TRUE
J 2
(-2125 1875);
DISPLAY 1.234043 (-2125 1875);
PAINT GREEN (-2125 1875);
DISPLAY INVISIBLE (-2125 1875);
FORCEPROP 1 LAST PATH I103
J 2
(-1800 2000);
DISPLAY 0.936170 (-1800 2000);
PAINT GREEN (-1800 2000);
DISPLAY INVISIBLE (-1800 2000);
FORCEADD TAP..6
R 2
(-1800 1750);
FORCEPROP 3 LASTPIN (-1850 1750) SIG_NAME M_J_DQ<3>
J 0
(-1840 1760);
DISPLAY 0.659574 (-1840 1760);
PAINT MONO (-1840 1760);
DISPLAY INVISIBLE (-1840 1760);
FORCEPROP 1 LASTPIN (-1850 1750) BN 3
J 2
(-1800 1760);
DISPLAY 0.617021 (-1800 1760);
PAINT PINK (-1800 1760);
FORCEPROP 2 LAST CDS_LIB mstr_standard
J 2
(-1800 1750);
DISPLAY 0.787234 (-1800 1750);
PAINT MONO (-1800 1750);
DISPLAY INVISIBLE (-1800 1750);
FORCEPROP 1 LAST BODY_TYPE PLUMBING
J 2
(-1800 1700);
DISPLAY 1.234043 (-1800 1700);
PAINT GREEN (-1800 1700);
DISPLAY INVISIBLE (-1800 1700);
FORCEPROP 1 LAST HDL_TAP TRUE
J 2
(-2125 1625);
DISPLAY 1.234043 (-2125 1625);
PAINT GREEN (-2125 1625);
DISPLAY INVISIBLE (-2125 1625);
FORCEPROP 1 LAST PATH I104
J 2
(-1800 1750);
DISPLAY 0.936170 (-1800 1750);
PAINT GREEN (-1800 1750);
DISPLAY INVISIBLE (-1800 1750);
FORCEADD TAP..6
R 2
(-1800 1850);
FORCEPROP 3 LASTPIN (-1850 1850) SIG_NAME M_J_DQ<5>
J 0
(-1840 1860);
DISPLAY 0.659574 (-1840 1860);
PAINT MONO (-1840 1860);
DISPLAY INVISIBLE (-1840 1860);
FORCEPROP 1 LASTPIN (-1850 1850) BN 5
J 2
(-1800 1860);
DISPLAY 0.617021 (-1800 1860);
PAINT PINK (-1800 1860);
FORCEPROP 2 LAST CDS_LIB mstr_standard
J 2
(-1800 1850);
DISPLAY 0.787234 (-1800 1850);
PAINT MONO (-1800 1850);
DISPLAY INVISIBLE (-1800 1850);
FORCEPROP 1 LAST BODY_TYPE PLUMBING
J 2
(-1800 1800);
DISPLAY 1.234043 (-1800 1800);
PAINT GREEN (-1800 1800);
DISPLAY INVISIBLE (-1800 1800);
FORCEPROP 1 LAST HDL_TAP TRUE
J 2
(-2125 1725);
DISPLAY 1.234043 (-2125 1725);
PAINT GREEN (-2125 1725);
DISPLAY INVISIBLE (-2125 1725);
FORCEPROP 1 LAST PATH I105
J 2
(-1800 1850);
DISPLAY 0.936170 (-1800 1850);
PAINT GREEN (-1800 1850);
DISPLAY INVISIBLE (-1800 1850);
FORCEADD TAP..6
R 2
(-1800 1800);
FORCEPROP 3 LASTPIN (-1850 1800) SIG_NAME M_J_DQ<2>
J 0
(-1840 1810);
DISPLAY 0.659574 (-1840 1810);
PAINT MONO (-1840 1810);
DISPLAY INVISIBLE (-1840 1810);
FORCEPROP 1 LASTPIN (-1850 1800) BN 2
J 2
(-1800 1810);
DISPLAY 0.617021 (-1800 1810);
PAINT PINK (-1800 1810);
FORCEPROP 2 LAST CDS_LIB mstr_standard
J 2
(-1800 1800);
DISPLAY 0.787234 (-1800 1800);
PAINT MONO (-1800 1800);
DISPLAY INVISIBLE (-1800 1800);
FORCEPROP 1 LAST BODY_TYPE PLUMBING
J 2
(-1800 1750);
DISPLAY 1.234043 (-1800 1750);
PAINT GREEN (-1800 1750);
DISPLAY INVISIBLE (-1800 1750);
FORCEPROP 1 LAST HDL_TAP TRUE
J 2
(-2125 1675);
DISPLAY 1.234043 (-2125 1675);
PAINT GREEN (-2125 1675);
DISPLAY INVISIBLE (-2125 1675);
FORCEPROP 1 LAST PATH I106
J 2
(-1800 1800);
DISPLAY 0.936170 (-1800 1800);
PAINT GREEN (-1800 1800);
DISPLAY INVISIBLE (-1800 1800);
FORCEADD TAP..6
R 2
(-1800 1950);
FORCEPROP 3 LASTPIN (-1850 1950) SIG_NAME M_J_DQ<7>
J 0
(-1840 1960);
DISPLAY 0.659574 (-1840 1960);
PAINT MONO (-1840 1960);
DISPLAY INVISIBLE (-1840 1960);
FORCEPROP 1 LASTPIN (-1850 1950) BN 7
J 2
(-1800 1960);
DISPLAY 0.617021 (-1800 1960);
PAINT PINK (-1800 1960);
FORCEPROP 2 LAST CDS_LIB mstr_standard
J 2
(-1800 1950);
DISPLAY 0.787234 (-1800 1950);
PAINT MONO (-1800 1950);
DISPLAY INVISIBLE (-1800 1950);
FORCEPROP 1 LAST BODY_TYPE PLUMBING
J 2
(-1800 1900);
DISPLAY 1.234043 (-1800 1900);
PAINT GREEN (-1800 1900);
DISPLAY INVISIBLE (-1800 1900);
FORCEPROP 1 LAST HDL_TAP TRUE
J 2
(-2125 1825);
DISPLAY 1.234043 (-2125 1825);
PAINT GREEN (-2125 1825);
DISPLAY INVISIBLE (-2125 1825);
FORCEPROP 1 LAST PATH I107
J 2
(-1800 1950);
DISPLAY 0.936170 (-1800 1950);
PAINT GREEN (-1800 1950);
DISPLAY INVISIBLE (-1800 1950);
FORCEADD TAP..6
R 2
(-1800 1900);
FORCEPROP 3 LASTPIN (-1850 1900) SIG_NAME M_J_DQ<4>
J 0
(-1840 1910);
DISPLAY 0.659574 (-1840 1910);
PAINT MONO (-1840 1910);
DISPLAY INVISIBLE (-1840 1910);
FORCEPROP 1 LASTPIN (-1850 1900) BN 4
J 2
(-1800 1910);
DISPLAY 0.617021 (-1800 1910);
PAINT PINK (-1800 1910);
FORCEPROP 2 LAST CDS_LIB mstr_standard
J 2
(-1800 1900);
DISPLAY 0.787234 (-1800 1900);
PAINT MONO (-1800 1900);
DISPLAY INVISIBLE (-1800 1900);
FORCEPROP 1 LAST BODY_TYPE PLUMBING
J 2
(-1800 1850);
DISPLAY 1.234043 (-1800 1850);
PAINT GREEN (-1800 1850);
DISPLAY INVISIBLE (-1800 1850);
FORCEPROP 1 LAST HDL_TAP TRUE
J 2
(-2125 1775);
DISPLAY 1.234043 (-2125 1775);
PAINT GREEN (-2125 1775);
DISPLAY INVISIBLE (-2125 1775);
FORCEPROP 1 LAST PATH I108
J 2
(-1800 1900);
DISPLAY 0.936170 (-1800 1900);
PAINT GREEN (-1800 1900);
DISPLAY INVISIBLE (-1800 1900);
FORCEADD TAP..6
R 2
(-1800 1700);
FORCEPROP 3 LASTPIN (-1850 1700) SIG_NAME M_J_DQ<0>
J 0
(-1840 1710);
DISPLAY 0.659574 (-1840 1710);
PAINT MONO (-1840 1710);
DISPLAY INVISIBLE (-1840 1710);
FORCEPROP 1 LASTPIN (-1850 1700) BN 0
J 2
(-1800 1710);
DISPLAY 0.617021 (-1800 1710);
PAINT PINK (-1800 1710);
FORCEPROP 2 LAST CDS_LIB mstr_standard
J 2
(-1800 1700);
DISPLAY 0.787234 (-1800 1700);
PAINT MONO (-1800 1700);
DISPLAY INVISIBLE (-1800 1700);
FORCEPROP 1 LAST BODY_TYPE PLUMBING
J 2
(-1800 1650);
DISPLAY 1.234043 (-1800 1650);
PAINT GREEN (-1800 1650);
DISPLAY INVISIBLE (-1800 1650);
FORCEPROP 1 LAST HDL_TAP TRUE
J 2
(-2125 1575);
DISPLAY 1.234043 (-2125 1575);
PAINT GREEN (-2125 1575);
DISPLAY INVISIBLE (-2125 1575);
FORCEPROP 1 LAST PATH I109
J 2
(-1800 1700);
DISPLAY 0.936170 (-1800 1700);
PAINT GREEN (-1800 1700);
DISPLAY INVISIBLE (-1800 1700);
FORCEADD TAP..6
R 2
(850 4500);
FORCEPROP 3 LASTPIN (800 4500) SIG_NAME M_J_DQS_DN<11>
J 0
(810 4510);
DISPLAY 0.659574 (810 4510);
PAINT MONO (810 4510);
DISPLAY INVISIBLE (810 4510);
FORCEPROP 1 LASTPIN (800 4500) BN 11
J 2
(850 4510);
DISPLAY 0.617021 (850 4510);
PAINT PINK (850 4510);
FORCEPROP 2 LAST CDS_LIB mstr_standard
J 0
(850 4500);
DISPLAY 0.787234 (850 4500);
PAINT MONO (850 4500);
DISPLAY INVISIBLE (850 4500);
FORCEPROP 1 LAST BODY_TYPE PLUMBING
J 2
(850 4450);
DISPLAY 1.234043 (850 4450);
PAINT GREEN (850 4450);
DISPLAY INVISIBLE (850 4450);
FORCEPROP 1 LAST HDL_TAP TRUE
J 2
(525 4375);
DISPLAY 1.234043 (525 4375);
PAINT GREEN (525 4375);
DISPLAY INVISIBLE (525 4375);
FORCEPROP 1 LAST PATH I11
J 2
(850 4500);
DISPLAY 0.936170 (850 4500);
PAINT GREEN (850 4500);
DISPLAY INVISIBLE (850 4500);
FORCEADD TAP..6
R 2
(-1800 1650);
FORCEPROP 3 LASTPIN (-1850 1650) SIG_NAME M_J_DQ<1>
J 0
(-1840 1660);
DISPLAY 0.659574 (-1840 1660);
PAINT MONO (-1840 1660);
DISPLAY INVISIBLE (-1840 1660);
FORCEPROP 1 LASTPIN (-1850 1650) BN 1
J 2
(-1800 1660);
DISPLAY 0.617021 (-1800 1660);
PAINT PINK (-1800 1660);
FORCEPROP 2 LAST CDS_LIB mstr_standard
J 2
(-1800 1650);
DISPLAY 0.787234 (-1800 1650);
PAINT MONO (-1800 1650);
DISPLAY INVISIBLE (-1800 1650);
FORCEPROP 1 LAST BODY_TYPE PLUMBING
J 2
(-1800 1600);
DISPLAY 1.234043 (-1800 1600);
PAINT GREEN (-1800 1600);
DISPLAY INVISIBLE (-1800 1600);
FORCEPROP 1 LAST HDL_TAP TRUE
J 2
(-2125 1525);
DISPLAY 1.234043 (-2125 1525);
PAINT GREEN (-2125 1525);
DISPLAY INVISIBLE (-2125 1525);
FORCEPROP 1 LAST PATH I110
J 2
(-1800 1650);
DISPLAY 0.936170 (-1800 1650);
PAINT GREEN (-1800 1650);
DISPLAY INVISIBLE (-1800 1650);
FORCEADD TAP..6
(-3300 4800);
FORCEPROP 3 LASTPIN (-3250 4800) SIG_NAME M_J_MA<17>
J 0
(-3240 4810);
DISPLAY 0.659574 (-3240 4810);
PAINT MONO (-3240 4810);
DISPLAY INVISIBLE (-3240 4810);
FORCEPROP 1 LASTPIN (-3250 4800) BN 17
J 0
(-3300 4810);
DISPLAY 0.617021 (-3300 4810);
PAINT PINK (-3300 4810);
FORCEPROP 2 LAST CDS_LIB mstr_standard
J 0
(-3300 4800);
DISPLAY 0.787234 (-3300 4800);
PAINT MONO (-3300 4800);
DISPLAY INVISIBLE (-3300 4800);
FORCEPROP 1 LAST BODY_TYPE PLUMBING
J 0
(-3300 4750);
DISPLAY 1.234043 (-3300 4750);
PAINT GREEN (-3300 4750);
DISPLAY INVISIBLE (-3300 4750);
FORCEPROP 1 LAST HDL_TAP TRUE
J 0
(-2975 4675);
DISPLAY 1.234043 (-2975 4675);
PAINT GREEN (-2975 4675);
DISPLAY INVISIBLE (-2975 4675);
FORCEPROP 1 LAST PATH I112
J 0
(-3300 4800);
DISPLAY 0.936170 (-3300 4800);
PAINT GREEN (-3300 4800);
DISPLAY INVISIBLE (-3300 4800);
FORCEADD OFFPAGE..1
(-3950 4850);
FORCEPROP 2 LAST $XR1 82 
J 0
(-4261 4850);
DISPLAY 0.638298 (-4261 4850);
PAINT MONO (-4261 4850);
FORCEPROP 2 LAST $XR0 59 
J 0
(-4171 4850);
DISPLAY 0.638298 (-4171 4850);
PAINT MONO (-4171 4850);
FORCEPROP 2 LAST CDS_LIB mstr_standard
J 0
(-3950 4850);
DISPLAY 0.787234 (-3950 4850);
PAINT MONO (-3950 4850);
DISPLAY INVISIBLE (-3950 4850);
FORCEPROP 1 LAST OFFPAGE TRUE
J 0
(-3625 4725);
DISPLAY 0.936170 (-3625 4725);
PAINT GREEN (-3625 4725);
DISPLAY INVISIBLE (-3625 4725);
FORCEPROP 1 LAST COMMENT_BODY TRUE
J 0
(-3825 4750);
DISPLAY 0.936170 (-3825 4750);
PAINT GREEN (-3825 4750);
DISPLAY INVISIBLE (-3825 4750);
FORCEPROP 2 LAST PATH I113
J 0
(-3900 4925);
DISPLAY 0.787234 (-3900 4925);
PAINT MONO (-3900 4925);
DISPLAY INVISIBLE (-3900 4925);
FORCEADD TAP..6
(-3300 4750);
FORCEPROP 3 LASTPIN (-3250 4750) SIG_NAME M_J_MA<16>
J 0
(-3240 4760);
DISPLAY 0.659574 (-3240 4760);
PAINT MONO (-3240 4760);
DISPLAY INVISIBLE (-3240 4760);
FORCEPROP 1 LASTPIN (-3250 4750) BN 16
J 0
(-3300 4760);
DISPLAY 0.617021 (-3300 4760);
PAINT PINK (-3300 4760);
FORCEPROP 2 LAST CDS_LIB mstr_standard
J 2
(-3300 4750);
DISPLAY 0.787234 (-3300 4750);
PAINT MONO (-3300 4750);
DISPLAY INVISIBLE (-3300 4750);
FORCEPROP 1 LAST BODY_TYPE PLUMBING
J 0
(-3300 4700);
DISPLAY 1.234043 (-3300 4700);
PAINT GREEN (-3300 4700);
DISPLAY INVISIBLE (-3300 4700);
FORCEPROP 1 LAST HDL_TAP TRUE
J 0
(-2975 4625);
DISPLAY 1.234043 (-2975 4625);
PAINT GREEN (-2975 4625);
DISPLAY INVISIBLE (-2975 4625);
FORCEPROP 1 LAST PATH I114
J 0
(-3300 4750);
DISPLAY 0.936170 (-3300 4750);
PAINT GREEN (-3300 4750);
DISPLAY INVISIBLE (-3300 4750);
FORCEADD TAP..6
(-3300 4700);
FORCEPROP 3 LASTPIN (-3250 4700) SIG_NAME M_J_MA<15>
J 0
(-3240 4710);
DISPLAY 0.659574 (-3240 4710);
PAINT MONO (-3240 4710);
DISPLAY INVISIBLE (-3240 4710);
FORCEPROP 1 LASTPIN (-3250 4700) BN 15
J 0
(-3300 4710);
DISPLAY 0.617021 (-3300 4710);
PAINT PINK (-3300 4710);
FORCEPROP 2 LAST CDS_LIB mstr_standard
J 2
(-3300 4700);
DISPLAY 0.787234 (-3300 4700);
PAINT MONO (-3300 4700);
DISPLAY INVISIBLE (-3300 4700);
FORCEPROP 1 LAST BODY_TYPE PLUMBING
J 0
(-3300 4650);
DISPLAY 1.234043 (-3300 4650);
PAINT GREEN (-3300 4650);
DISPLAY INVISIBLE (-3300 4650);
FORCEPROP 1 LAST HDL_TAP TRUE
J 0
(-2975 4575);
DISPLAY 1.234043 (-2975 4575);
PAINT GREEN (-2975 4575);
DISPLAY INVISIBLE (-2975 4575);
FORCEPROP 1 LAST PATH I115
J 0
(-3300 4700);
DISPLAY 0.936170 (-3300 4700);
PAINT GREEN (-3300 4700);
DISPLAY INVISIBLE (-3300 4700);
FORCEADD TAP..6
(-3300 4650);
FORCEPROP 3 LASTPIN (-3250 4650) SIG_NAME M_J_MA<14>
J 0
(-3240 4660);
DISPLAY 0.659574 (-3240 4660);
PAINT MONO (-3240 4660);
DISPLAY INVISIBLE (-3240 4660);
FORCEPROP 1 LASTPIN (-3250 4650) BN 14
J 0
(-3300 4660);
DISPLAY 0.617021 (-3300 4660);
PAINT PINK (-3300 4660);
FORCEPROP 2 LAST CDS_LIB mstr_standard
J 2
(-3300 4650);
DISPLAY 0.787234 (-3300 4650);
PAINT MONO (-3300 4650);
DISPLAY INVISIBLE (-3300 4650);
FORCEPROP 1 LAST BODY_TYPE PLUMBING
J 0
(-3300 4600);
DISPLAY 1.234043 (-3300 4600);
PAINT GREEN (-3300 4600);
DISPLAY INVISIBLE (-3300 4600);
FORCEPROP 1 LAST HDL_TAP TRUE
J 0
(-2975 4525);
DISPLAY 1.234043 (-2975 4525);
PAINT GREEN (-2975 4525);
DISPLAY INVISIBLE (-2975 4525);
FORCEPROP 1 LAST PATH I116
J 0
(-3300 4650);
DISPLAY 0.936170 (-3300 4650);
PAINT GREEN (-3300 4650);
DISPLAY INVISIBLE (-3300 4650);
FORCEADD TAP..6
(-3300 4600);
FORCEPROP 3 LASTPIN (-3250 4600) SIG_NAME M_J_MA<13>
J 0
(-3240 4610);
DISPLAY 0.659574 (-3240 4610);
PAINT MONO (-3240 4610);
DISPLAY INVISIBLE (-3240 4610);
FORCEPROP 1 LASTPIN (-3250 4600) BN 13
J 0
(-3300 4610);
DISPLAY 0.617021 (-3300 4610);
PAINT PINK (-3300 4610);
FORCEPROP 2 LAST CDS_LIB mstr_standard
J 2
(-3300 4600);
DISPLAY 0.787234 (-3300 4600);
PAINT MONO (-3300 4600);
DISPLAY INVISIBLE (-3300 4600);
FORCEPROP 1 LAST BODY_TYPE PLUMBING
J 0
(-3300 4550);
DISPLAY 1.234043 (-3300 4550);
PAINT GREEN (-3300 4550);
DISPLAY INVISIBLE (-3300 4550);
FORCEPROP 1 LAST HDL_TAP TRUE
J 0
(-2975 4475);
DISPLAY 1.234043 (-2975 4475);
PAINT GREEN (-2975 4475);
DISPLAY INVISIBLE (-2975 4475);
FORCEPROP 1 LAST PATH I117
J 0
(-3300 4600);
DISPLAY 0.936170 (-3300 4600);
PAINT GREEN (-3300 4600);
DISPLAY INVISIBLE (-3300 4600);
FORCEADD TAP..6
(-3300 4550);
FORCEPROP 3 LASTPIN (-3250 4550) SIG_NAME M_J_MA<12>
J 0
(-3240 4560);
DISPLAY 0.659574 (-3240 4560);
PAINT MONO (-3240 4560);
DISPLAY INVISIBLE (-3240 4560);
FORCEPROP 1 LASTPIN (-3250 4550) BN 12
J 0
(-3300 4560);
DISPLAY 0.617021 (-3300 4560);
PAINT PINK (-3300 4560);
FORCEPROP 2 LAST CDS_LIB mstr_standard
J 2
(-3300 4550);
DISPLAY 0.787234 (-3300 4550);
PAINT MONO (-3300 4550);
DISPLAY INVISIBLE (-3300 4550);
FORCEPROP 1 LAST BODY_TYPE PLUMBING
J 0
(-3300 4500);
DISPLAY 1.234043 (-3300 4500);
PAINT GREEN (-3300 4500);
DISPLAY INVISIBLE (-3300 4500);
FORCEPROP 1 LAST HDL_TAP TRUE
J 0
(-2975 4425);
DISPLAY 1.234043 (-2975 4425);
PAINT GREEN (-2975 4425);
DISPLAY INVISIBLE (-2975 4425);
FORCEPROP 1 LAST PATH I118
J 0
(-3300 4550);
DISPLAY 0.936170 (-3300 4550);
PAINT GREEN (-3300 4550);
DISPLAY INVISIBLE (-3300 4550);
FORCEADD TAP..6
(-3300 4500);
FORCEPROP 3 LASTPIN (-3250 4500) SIG_NAME M_J_MA<11>
J 0
(-3240 4510);
DISPLAY 0.659574 (-3240 4510);
PAINT MONO (-3240 4510);
DISPLAY INVISIBLE (-3240 4510);
FORCEPROP 1 LASTPIN (-3250 4500) BN 11
J 0
(-3300 4510);
DISPLAY 0.617021 (-3300 4510);
PAINT PINK (-3300 4510);
FORCEPROP 2 LAST CDS_LIB mstr_standard
J 2
(-3300 4500);
DISPLAY 0.787234 (-3300 4500);
PAINT MONO (-3300 4500);
DISPLAY INVISIBLE (-3300 4500);
FORCEPROP 1 LAST BODY_TYPE PLUMBING
J 0
(-3300 4450);
DISPLAY 1.234043 (-3300 4450);
PAINT GREEN (-3300 4450);
DISPLAY INVISIBLE (-3300 4450);
FORCEPROP 1 LAST HDL_TAP TRUE
J 0
(-2975 4375);
DISPLAY 1.234043 (-2975 4375);
PAINT GREEN (-2975 4375);
DISPLAY INVISIBLE (-2975 4375);
FORCEPROP 1 LAST PATH I119
J 0
(-3300 4500);
DISPLAY 0.936170 (-3300 4500);
PAINT GREEN (-3300 4500);
DISPLAY INVISIBLE (-3300 4500);
FORCEADD TAP..6
R 2
(650 4750);
FORCEPROP 3 LASTPIN (600 4750) SIG_NAME M_J_DQS_DP<13>
J 0
(610 4760);
DISPLAY 0.659574 (610 4760);
PAINT MONO (610 4760);
DISPLAY INVISIBLE (610 4760);
FORCEPROP 1 LASTPIN (600 4750) BN 13
J 2
(650 4760);
DISPLAY 0.617021 (650 4760);
PAINT PINK (650 4760);
FORCEPROP 2 LAST CDS_LIB mstr_standard
J 0
(650 4750);
DISPLAY 0.787234 (650 4750);
PAINT MONO (650 4750);
DISPLAY INVISIBLE (650 4750);
FORCEPROP 1 LAST BODY_TYPE PLUMBING
J 2
(650 4700);
DISPLAY 1.234043 (650 4700);
PAINT GREEN (650 4700);
DISPLAY INVISIBLE (650 4700);
FORCEPROP 1 LAST HDL_TAP TRUE
J 2
(325 4625);
DISPLAY 1.234043 (325 4625);
PAINT GREEN (325 4625);
DISPLAY INVISIBLE (325 4625);
FORCEPROP 1 LAST PATH I12
J 2
(650 4750);
DISPLAY 0.936170 (650 4750);
PAINT GREEN (650 4750);
DISPLAY INVISIBLE (650 4750);
FORCEADD TAP..6
(-3300 4450);
FORCEPROP 3 LASTPIN (-3250 4450) SIG_NAME M_J_MA<10>
J 0
(-3240 4460);
DISPLAY 0.659574 (-3240 4460);
PAINT MONO (-3240 4460);
DISPLAY INVISIBLE (-3240 4460);
FORCEPROP 1 LASTPIN (-3250 4450) BN 10
J 0
(-3300 4460);
DISPLAY 0.617021 (-3300 4460);
PAINT PINK (-3300 4460);
FORCEPROP 2 LAST CDS_LIB mstr_standard
J 2
(-3300 4450);
DISPLAY 0.787234 (-3300 4450);
PAINT MONO (-3300 4450);
DISPLAY INVISIBLE (-3300 4450);
FORCEPROP 1 LAST BODY_TYPE PLUMBING
J 0
(-3300 4400);
DISPLAY 1.234043 (-3300 4400);
PAINT GREEN (-3300 4400);
DISPLAY INVISIBLE (-3300 4400);
FORCEPROP 1 LAST HDL_TAP TRUE
J 0
(-2975 4325);
DISPLAY 1.234043 (-2975 4325);
PAINT GREEN (-2975 4325);
DISPLAY INVISIBLE (-2975 4325);
FORCEPROP 1 LAST PATH I120
J 0
(-3300 4450);
DISPLAY 0.936170 (-3300 4450);
PAINT GREEN (-3300 4450);
DISPLAY INVISIBLE (-3300 4450);
FORCEADD TAP..6
(-3300 4400);
FORCEPROP 3 LASTPIN (-3250 4400) SIG_NAME M_J_MA<9>
J 0
(-3240 4410);
DISPLAY 0.659574 (-3240 4410);
PAINT MONO (-3240 4410);
DISPLAY INVISIBLE (-3240 4410);
FORCEPROP 1 LASTPIN (-3250 4400) BN 9
J 0
(-3300 4410);
DISPLAY 0.617021 (-3300 4410);
PAINT PINK (-3300 4410);
FORCEPROP 2 LAST CDS_LIB mstr_standard
J 2
(-3300 4400);
DISPLAY 0.787234 (-3300 4400);
PAINT MONO (-3300 4400);
DISPLAY INVISIBLE (-3300 4400);
FORCEPROP 1 LAST BODY_TYPE PLUMBING
J 0
(-3300 4350);
DISPLAY 1.234043 (-3300 4350);
PAINT GREEN (-3300 4350);
DISPLAY INVISIBLE (-3300 4350);
FORCEPROP 1 LAST HDL_TAP TRUE
J 0
(-2975 4275);
DISPLAY 1.234043 (-2975 4275);
PAINT GREEN (-2975 4275);
DISPLAY INVISIBLE (-2975 4275);
FORCEPROP 1 LAST PATH I121
J 0
(-3300 4400);
DISPLAY 0.936170 (-3300 4400);
PAINT GREEN (-3300 4400);
DISPLAY INVISIBLE (-3300 4400);
FORCEADD TAP..6
(-3300 4350);
FORCEPROP 3 LASTPIN (-3250 4350) SIG_NAME M_J_MA<8>
J 0
(-3240 4360);
DISPLAY 0.659574 (-3240 4360);
PAINT MONO (-3240 4360);
DISPLAY INVISIBLE (-3240 4360);
FORCEPROP 1 LASTPIN (-3250 4350) BN 8
J 0
(-3300 4360);
DISPLAY 0.617021 (-3300 4360);
PAINT PINK (-3300 4360);
FORCEPROP 2 LAST CDS_LIB mstr_standard
J 2
(-3300 4350);
DISPLAY 0.787234 (-3300 4350);
PAINT MONO (-3300 4350);
DISPLAY INVISIBLE (-3300 4350);
FORCEPROP 1 LAST BODY_TYPE PLUMBING
J 0
(-3300 4300);
DISPLAY 1.234043 (-3300 4300);
PAINT GREEN (-3300 4300);
DISPLAY INVISIBLE (-3300 4300);
FORCEPROP 1 LAST HDL_TAP TRUE
J 0
(-2975 4225);
DISPLAY 1.234043 (-2975 4225);
PAINT GREEN (-2975 4225);
DISPLAY INVISIBLE (-2975 4225);
FORCEPROP 1 LAST PATH I122
J 0
(-3300 4350);
DISPLAY 0.936170 (-3300 4350);
PAINT GREEN (-3300 4350);
DISPLAY INVISIBLE (-3300 4350);
FORCEADD TAP..6
(-3300 4300);
FORCEPROP 3 LASTPIN (-3250 4300) SIG_NAME M_J_MA<7>
J 0
(-3240 4310);
DISPLAY 0.659574 (-3240 4310);
PAINT MONO (-3240 4310);
DISPLAY INVISIBLE (-3240 4310);
FORCEPROP 1 LASTPIN (-3250 4300) BN 7
J 0
(-3300 4310);
DISPLAY 0.617021 (-3300 4310);
PAINT PINK (-3300 4310);
FORCEPROP 2 LAST CDS_LIB mstr_standard
J 2
(-3300 4300);
DISPLAY 0.787234 (-3300 4300);
PAINT MONO (-3300 4300);
DISPLAY INVISIBLE (-3300 4300);
FORCEPROP 1 LAST BODY_TYPE PLUMBING
J 0
(-3300 4250);
DISPLAY 1.234043 (-3300 4250);
PAINT GREEN (-3300 4250);
DISPLAY INVISIBLE (-3300 4250);
FORCEPROP 1 LAST HDL_TAP TRUE
J 0
(-2975 4175);
DISPLAY 1.234043 (-2975 4175);
PAINT GREEN (-2975 4175);
DISPLAY INVISIBLE (-2975 4175);
FORCEPROP 1 LAST PATH I123
J 0
(-3300 4300);
DISPLAY 0.936170 (-3300 4300);
PAINT GREEN (-3300 4300);
DISPLAY INVISIBLE (-3300 4300);
FORCEADD TAP..6
(-3300 4250);
FORCEPROP 3 LASTPIN (-3250 4250) SIG_NAME M_J_MA<6>
J 0
(-3240 4260);
DISPLAY 0.659574 (-3240 4260);
PAINT MONO (-3240 4260);
DISPLAY INVISIBLE (-3240 4260);
FORCEPROP 1 LASTPIN (-3250 4250) BN 6
J 0
(-3300 4260);
DISPLAY 0.617021 (-3300 4260);
PAINT PINK (-3300 4260);
FORCEPROP 2 LAST CDS_LIB mstr_standard
J 2
(-3300 4250);
DISPLAY 0.787234 (-3300 4250);
PAINT MONO (-3300 4250);
DISPLAY INVISIBLE (-3300 4250);
FORCEPROP 1 LAST BODY_TYPE PLUMBING
J 0
(-3300 4200);
DISPLAY 1.234043 (-3300 4200);
PAINT GREEN (-3300 4200);
DISPLAY INVISIBLE (-3300 4200);
FORCEPROP 1 LAST HDL_TAP TRUE
J 0
(-2975 4125);
DISPLAY 1.234043 (-2975 4125);
PAINT GREEN (-2975 4125);
DISPLAY INVISIBLE (-2975 4125);
FORCEPROP 1 LAST PATH I124
J 0
(-3300 4250);
DISPLAY 0.936170 (-3300 4250);
PAINT GREEN (-3300 4250);
DISPLAY INVISIBLE (-3300 4250);
FORCEADD TAP..6
(-3300 4200);
FORCEPROP 3 LASTPIN (-3250 4200) SIG_NAME M_J_MA<5>
J 0
(-3240 4210);
DISPLAY 0.659574 (-3240 4210);
PAINT MONO (-3240 4210);
DISPLAY INVISIBLE (-3240 4210);
FORCEPROP 1 LASTPIN (-3250 4200) BN 5
J 0
(-3300 4210);
DISPLAY 0.617021 (-3300 4210);
PAINT PINK (-3300 4210);
FORCEPROP 2 LAST CDS_LIB mstr_standard
J 2
(-3300 4200);
DISPLAY 0.787234 (-3300 4200);
PAINT MONO (-3300 4200);
DISPLAY INVISIBLE (-3300 4200);
FORCEPROP 1 LAST BODY_TYPE PLUMBING
J 0
(-3300 4150);
DISPLAY 1.234043 (-3300 4150);
PAINT GREEN (-3300 4150);
DISPLAY INVISIBLE (-3300 4150);
FORCEPROP 1 LAST HDL_TAP TRUE
J 0
(-2975 4075);
DISPLAY 1.234043 (-2975 4075);
PAINT GREEN (-2975 4075);
DISPLAY INVISIBLE (-2975 4075);
FORCEPROP 1 LAST PATH I125
J 0
(-3300 4200);
DISPLAY 0.936170 (-3300 4200);
PAINT GREEN (-3300 4200);
DISPLAY INVISIBLE (-3300 4200);
FORCEADD TAP..6
(-3300 4150);
FORCEPROP 3 LASTPIN (-3250 4150) SIG_NAME M_J_MA<4>
J 0
(-3240 4160);
DISPLAY 0.659574 (-3240 4160);
PAINT MONO (-3240 4160);
DISPLAY INVISIBLE (-3240 4160);
FORCEPROP 1 LASTPIN (-3250 4150) BN 4
J 0
(-3300 4160);
DISPLAY 0.617021 (-3300 4160);
PAINT PINK (-3300 4160);
FORCEPROP 2 LAST CDS_LIB mstr_standard
J 2
(-3300 4150);
DISPLAY 0.787234 (-3300 4150);
PAINT MONO (-3300 4150);
DISPLAY INVISIBLE (-3300 4150);
FORCEPROP 1 LAST BODY_TYPE PLUMBING
J 0
(-3300 4100);
DISPLAY 1.234043 (-3300 4100);
PAINT GREEN (-3300 4100);
DISPLAY INVISIBLE (-3300 4100);
FORCEPROP 1 LAST HDL_TAP TRUE
J 0
(-2975 4025);
DISPLAY 1.234043 (-2975 4025);
PAINT GREEN (-2975 4025);
DISPLAY INVISIBLE (-2975 4025);
FORCEPROP 1 LAST PATH I126
J 0
(-3300 4150);
DISPLAY 0.936170 (-3300 4150);
PAINT GREEN (-3300 4150);
DISPLAY INVISIBLE (-3300 4150);
FORCEADD TAP..6
(-3300 4100);
FORCEPROP 3 LASTPIN (-3250 4100) SIG_NAME M_J_MA<3>
J 0
(-3240 4110);
DISPLAY 0.659574 (-3240 4110);
PAINT MONO (-3240 4110);
DISPLAY INVISIBLE (-3240 4110);
FORCEPROP 1 LASTPIN (-3250 4100) BN 3
J 0
(-3300 4110);
DISPLAY 0.617021 (-3300 4110);
PAINT PINK (-3300 4110);
FORCEPROP 2 LAST CDS_LIB mstr_standard
J 2
(-3300 4100);
DISPLAY 0.787234 (-3300 4100);
PAINT MONO (-3300 4100);
DISPLAY INVISIBLE (-3300 4100);
FORCEPROP 1 LAST BODY_TYPE PLUMBING
J 0
(-3300 4050);
DISPLAY 1.234043 (-3300 4050);
PAINT GREEN (-3300 4050);
DISPLAY INVISIBLE (-3300 4050);
FORCEPROP 1 LAST HDL_TAP TRUE
J 0
(-2975 3975);
DISPLAY 1.234043 (-2975 3975);
PAINT GREEN (-2975 3975);
DISPLAY INVISIBLE (-2975 3975);
FORCEPROP 1 LAST PATH I127
J 0
(-3300 4100);
DISPLAY 0.936170 (-3300 4100);
PAINT GREEN (-3300 4100);
DISPLAY INVISIBLE (-3300 4100);
FORCEADD TAP..6
(-3300 4050);
FORCEPROP 3 LASTPIN (-3250 4050) SIG_NAME M_J_MA<2>
J 0
(-3240 4060);
DISPLAY 0.659574 (-3240 4060);
PAINT MONO (-3240 4060);
DISPLAY INVISIBLE (-3240 4060);
FORCEPROP 1 LASTPIN (-3250 4050) BN 2
J 0
(-3300 4060);
DISPLAY 0.617021 (-3300 4060);
PAINT PINK (-3300 4060);
FORCEPROP 2 LAST CDS_LIB mstr_standard
J 2
(-3300 4050);
DISPLAY 0.787234 (-3300 4050);
PAINT MONO (-3300 4050);
DISPLAY INVISIBLE (-3300 4050);
FORCEPROP 1 LAST BODY_TYPE PLUMBING
J 0
(-3300 4000);
DISPLAY 1.234043 (-3300 4000);
PAINT GREEN (-3300 4000);
DISPLAY INVISIBLE (-3300 4000);
FORCEPROP 1 LAST HDL_TAP TRUE
J 0
(-2975 3925);
DISPLAY 1.234043 (-2975 3925);
PAINT GREEN (-2975 3925);
DISPLAY INVISIBLE (-2975 3925);
FORCEPROP 1 LAST PATH I128
J 0
(-3300 4050);
DISPLAY 0.936170 (-3300 4050);
PAINT GREEN (-3300 4050);
DISPLAY INVISIBLE (-3300 4050);
FORCEADD TAP..6
(-3300 4000);
FORCEPROP 3 LASTPIN (-3250 4000) SIG_NAME M_J_MA<1>
J 0
(-3240 4010);
DISPLAY 0.659574 (-3240 4010);
PAINT MONO (-3240 4010);
DISPLAY INVISIBLE (-3240 4010);
FORCEPROP 1 LASTPIN (-3250 4000) BN 1
J 0
(-3300 4010);
DISPLAY 0.617021 (-3300 4010);
PAINT PINK (-3300 4010);
FORCEPROP 2 LAST CDS_LIB mstr_standard
J 2
(-3300 4000);
DISPLAY 0.787234 (-3300 4000);
PAINT MONO (-3300 4000);
DISPLAY INVISIBLE (-3300 4000);
FORCEPROP 1 LAST BODY_TYPE PLUMBING
J 0
(-3300 3950);
DISPLAY 1.234043 (-3300 3950);
PAINT GREEN (-3300 3950);
DISPLAY INVISIBLE (-3300 3950);
FORCEPROP 1 LAST HDL_TAP TRUE
J 0
(-2975 3875);
DISPLAY 1.234043 (-2975 3875);
PAINT GREEN (-2975 3875);
DISPLAY INVISIBLE (-2975 3875);
FORCEPROP 1 LAST PATH I129
J 0
(-3300 4000);
DISPLAY 0.936170 (-3300 4000);
PAINT GREEN (-3300 4000);
DISPLAY INVISIBLE (-3300 4000);
FORCEADD TAP..6
R 2
(650 4850);
FORCEPROP 3 LASTPIN (600 4850) SIG_NAME M_J_DQS_DP<14>
J 0
(610 4860);
DISPLAY 0.659574 (610 4860);
PAINT MONO (610 4860);
DISPLAY INVISIBLE (610 4860);
FORCEPROP 1 LASTPIN (600 4850) BN 14
J 2
(650 4860);
DISPLAY 0.617021 (650 4860);
PAINT PINK (650 4860);
FORCEPROP 2 LAST CDS_LIB mstr_standard
J 0
(650 4850);
DISPLAY 0.787234 (650 4850);
PAINT MONO (650 4850);
DISPLAY INVISIBLE (650 4850);
FORCEPROP 1 LAST BODY_TYPE PLUMBING
J 2
(650 4800);
DISPLAY 1.234043 (650 4800);
PAINT GREEN (650 4800);
DISPLAY INVISIBLE (650 4800);
FORCEPROP 1 LAST HDL_TAP TRUE
J 2
(325 4725);
DISPLAY 1.234043 (325 4725);
PAINT GREEN (325 4725);
DISPLAY INVISIBLE (325 4725);
FORCEPROP 1 LAST PATH I13
J 2
(650 4850);
DISPLAY 0.936170 (650 4850);
PAINT GREEN (650 4850);
DISPLAY INVISIBLE (650 4850);
FORCEADD TAP..6
(-3300 3950);
FORCEPROP 3 LASTPIN (-3250 3950) SIG_NAME M_J_MA<0>
J 0
(-3240 3960);
DISPLAY 0.659574 (-3240 3960);
PAINT MONO (-3240 3960);
DISPLAY INVISIBLE (-3240 3960);
FORCEPROP 1 LASTPIN (-3250 3950) BN 0
J 0
(-3300 3960);
DISPLAY 0.617021 (-3300 3960);
PAINT PINK (-3300 3960);
FORCEPROP 2 LAST CDS_LIB mstr_standard
J 2
(-3300 3950);
DISPLAY 0.787234 (-3300 3950);
PAINT MONO (-3300 3950);
DISPLAY INVISIBLE (-3300 3950);
FORCEPROP 1 LAST BODY_TYPE PLUMBING
J 0
(-3300 3900);
DISPLAY 1.234043 (-3300 3900);
PAINT GREEN (-3300 3900);
DISPLAY INVISIBLE (-3300 3900);
FORCEPROP 1 LAST HDL_TAP TRUE
J 0
(-2975 3825);
DISPLAY 1.234043 (-2975 3825);
PAINT GREEN (-2975 3825);
DISPLAY INVISIBLE (-2975 3825);
FORCEPROP 1 LAST PATH I130
J 0
(-3300 3950);
DISPLAY 0.936170 (-3300 3950);
PAINT GREEN (-3300 3950);
DISPLAY INVISIBLE (-3300 3950);
FORCEADD TAP..6
(-3300 3850);
FORCEPROP 3 LASTPIN (-3250 3850) SIG_NAME M_J_BA<1>
J 0
(-3240 3860);
DISPLAY 0.659574 (-3240 3860);
PAINT MONO (-3240 3860);
DISPLAY INVISIBLE (-3240 3860);
FORCEPROP 1 LASTPIN (-3250 3850) BN 1
J 0
(-3300 3860);
DISPLAY 0.617021 (-3300 3860);
PAINT PINK (-3300 3860);
FORCEPROP 2 LAST CDS_LIB mstr_standard
J 0
(-3300 3850);
DISPLAY 0.787234 (-3300 3850);
PAINT MONO (-3300 3850);
DISPLAY INVISIBLE (-3300 3850);
FORCEPROP 1 LAST BODY_TYPE PLUMBING
J 0
(-3300 3800);
DISPLAY 1.234043 (-3300 3800);
PAINT GREEN (-3300 3800);
DISPLAY INVISIBLE (-3300 3800);
FORCEPROP 1 LAST HDL_TAP TRUE
J 0
(-2975 3725);
DISPLAY 1.234043 (-2975 3725);
PAINT GREEN (-2975 3725);
DISPLAY INVISIBLE (-2975 3725);
FORCEPROP 1 LAST PATH I131
J 0
(-3300 3850);
DISPLAY 0.936170 (-3300 3850);
PAINT GREEN (-3300 3850);
DISPLAY INVISIBLE (-3300 3850);
FORCEADD TAP..6
(-3300 3800);
FORCEPROP 3 LASTPIN (-3250 3800) SIG_NAME M_J_BA<0>
J 0
(-3240 3810);
DISPLAY 0.659574 (-3240 3810);
PAINT MONO (-3240 3810);
DISPLAY INVISIBLE (-3240 3810);
FORCEPROP 1 LASTPIN (-3250 3800) BN 0
J 0
(-3300 3810);
DISPLAY 0.617021 (-3300 3810);
PAINT PINK (-3300 3810);
FORCEPROP 2 LAST CDS_LIB mstr_standard
J 0
(-3300 3800);
DISPLAY 0.787234 (-3300 3800);
PAINT MONO (-3300 3800);
DISPLAY INVISIBLE (-3300 3800);
FORCEPROP 1 LAST BODY_TYPE PLUMBING
J 0
(-3300 3750);
DISPLAY 1.234043 (-3300 3750);
PAINT GREEN (-3300 3750);
DISPLAY INVISIBLE (-3300 3750);
FORCEPROP 1 LAST HDL_TAP TRUE
J 0
(-2975 3675);
DISPLAY 1.234043 (-2975 3675);
PAINT GREEN (-2975 3675);
DISPLAY INVISIBLE (-2975 3675);
FORCEPROP 1 LAST PATH I132
J 0
(-3300 3800);
DISPLAY 0.936170 (-3300 3800);
PAINT GREEN (-3300 3800);
DISPLAY INVISIBLE (-3300 3800);
FORCEADD OFFPAGE..1
(-3950 3900);
FORCEPROP 2 LAST $XR1 82 
J 0
(-4261 3900);
DISPLAY 0.638298 (-4261 3900);
PAINT MONO (-4261 3900);
FORCEPROP 2 LAST $XR0 59 
J 0
(-4171 3900);
DISPLAY 0.638298 (-4171 3900);
PAINT MONO (-4171 3900);
FORCEPROP 2 LAST CDS_LIB mstr_standard
J 0
(-3950 3900);
DISPLAY 0.787234 (-3950 3900);
PAINT MONO (-3950 3900);
DISPLAY INVISIBLE (-3950 3900);
FORCEPROP 1 LAST OFFPAGE TRUE
J 0
(-3625 3775);
DISPLAY 0.936170 (-3625 3775);
PAINT GREEN (-3625 3775);
DISPLAY INVISIBLE (-3625 3775);
FORCEPROP 1 LAST COMMENT_BODY TRUE
J 0
(-3825 3800);
DISPLAY 0.936170 (-3825 3800);
PAINT GREEN (-3825 3800);
DISPLAY INVISIBLE (-3825 3800);
FORCEPROP 2 LAST PATH I133
J 0
(-3900 3975);
DISPLAY 0.787234 (-3900 3975);
PAINT MONO (-3900 3975);
DISPLAY INVISIBLE (-3900 3975);
FORCEADD TAP..6
(-3300 3750);
FORCEPROP 3 LASTPIN (-3250 3750) SIG_NAME M_J_BG<1>
J 0
(-3240 3760);
DISPLAY 0.659574 (-3240 3760);
PAINT MONO (-3240 3760);
DISPLAY INVISIBLE (-3240 3760);
FORCEPROP 1 LASTPIN (-3250 3750) BN 1
J 0
(-3300 3760);
DISPLAY 0.617021 (-3300 3760);
PAINT PINK (-3300 3760);
FORCEPROP 2 LAST CDS_LIB mstr_standard
J 0
(-3300 3750);
DISPLAY 0.787234 (-3300 3750);
PAINT MONO (-3300 3750);
DISPLAY INVISIBLE (-3300 3750);
FORCEPROP 1 LAST BODY_TYPE PLUMBING
J 0
(-3300 3700);
DISPLAY 1.234043 (-3300 3700);
PAINT GREEN (-3300 3700);
DISPLAY INVISIBLE (-3300 3700);
FORCEPROP 1 LAST HDL_TAP TRUE
J 0
(-2975 3625);
DISPLAY 1.234043 (-2975 3625);
PAINT GREEN (-2975 3625);
DISPLAY INVISIBLE (-2975 3625);
FORCEPROP 1 LAST PATH I134
J 0
(-3300 3750);
DISPLAY 0.936170 (-3300 3750);
PAINT GREEN (-3300 3750);
DISPLAY INVISIBLE (-3300 3750);
FORCEADD TAP..6
(-3300 3700);
FORCEPROP 3 LASTPIN (-3250 3700) SIG_NAME M_J_BG<0>
J 0
(-3240 3710);
DISPLAY 0.659574 (-3240 3710);
PAINT MONO (-3240 3710);
DISPLAY INVISIBLE (-3240 3710);
FORCEPROP 1 LASTPIN (-3250 3700) BN 0
J 0
(-3300 3710);
DISPLAY 0.617021 (-3300 3710);
PAINT PINK (-3300 3710);
FORCEPROP 2 LAST CDS_LIB mstr_standard
J 0
(-3300 3700);
DISPLAY 0.787234 (-3300 3700);
PAINT MONO (-3300 3700);
DISPLAY INVISIBLE (-3300 3700);
FORCEPROP 1 LAST BODY_TYPE PLUMBING
J 0
(-3300 3650);
DISPLAY 1.234043 (-3300 3650);
PAINT GREEN (-3300 3650);
DISPLAY INVISIBLE (-3300 3650);
FORCEPROP 1 LAST HDL_TAP TRUE
J 0
(-2975 3575);
DISPLAY 1.234043 (-2975 3575);
PAINT GREEN (-2975 3575);
DISPLAY INVISIBLE (-2975 3575);
FORCEPROP 1 LAST PATH I135
J 0
(-3300 3700);
DISPLAY 0.936170 (-3300 3700);
PAINT GREEN (-3300 3700);
DISPLAY INVISIBLE (-3300 3700);
FORCEADD OFFPAGE..1
(-3950 3400);
FORCEPROP 2 LAST $XR1 82 
J 0
(-4261 3400);
DISPLAY 0.638298 (-4261 3400);
PAINT MONO (-4261 3400);
FORCEPROP 2 LAST $XR0 59 
J 0
(-4171 3400);
DISPLAY 0.638298 (-4171 3400);
PAINT MONO (-4171 3400);
FORCEPROP 2 LAST CDS_LIB mstr_standard
J 0
(-3950 3400);
DISPLAY 0.787234 (-3950 3400);
PAINT MONO (-3950 3400);
DISPLAY INVISIBLE (-3950 3400);
FORCEPROP 1 LAST OFFPAGE TRUE
J 0
(-3625 3275);
DISPLAY 0.936170 (-3625 3275);
PAINT GREEN (-3625 3275);
DISPLAY INVISIBLE (-3625 3275);
FORCEPROP 1 LAST COMMENT_BODY TRUE
J 0
(-3825 3300);
DISPLAY 0.936170 (-3825 3300);
PAINT GREEN (-3825 3300);
DISPLAY INVISIBLE (-3825 3300);
FORCEPROP 2 LAST PATH I136
J 0
(-3900 3475);
DISPLAY 0.787234 (-3900 3475);
PAINT MONO (-3900 3475);
DISPLAY INVISIBLE (-3900 3475);
FORCEADD TAP..6
(-3300 2750);
FORCEPROP 3 LASTPIN (-3250 2750) SIG_NAME M_J_ECC<6>
J 0
(-3240 2760);
DISPLAY 0.659574 (-3240 2760);
PAINT MONO (-3240 2760);
DISPLAY INVISIBLE (-3240 2760);
FORCEPROP 1 LASTPIN (-3250 2750) BN 6
J 0
(-3300 2760);
DISPLAY 0.617021 (-3300 2760);
PAINT PINK (-3300 2760);
FORCEPROP 2 LAST CDS_LIB mstr_standard
J 0
(-3300 2750);
DISPLAY 0.787234 (-3300 2750);
PAINT MONO (-3300 2750);
DISPLAY INVISIBLE (-3300 2750);
FORCEPROP 1 LAST BODY_TYPE PLUMBING
J 0
(-3300 2700);
DISPLAY 1.234043 (-3300 2700);
PAINT GREEN (-3300 2700);
DISPLAY INVISIBLE (-3300 2700);
FORCEPROP 1 LAST HDL_TAP TRUE
J 0
(-2975 2625);
DISPLAY 1.234043 (-2975 2625);
PAINT GREEN (-2975 2625);
DISPLAY INVISIBLE (-2975 2625);
FORCEPROP 1 LAST PATH I137
J 0
(-3300 2750);
DISPLAY 0.936170 (-3300 2750);
PAINT GREEN (-3300 2750);
DISPLAY INVISIBLE (-3300 2750);
FORCEADD OFFPAGE..1
(-3950 3800);
FORCEPROP 2 LAST $XR1 82 
J 0
(-4261 3800);
DISPLAY 0.638298 (-4261 3800);
PAINT MONO (-4261 3800);
FORCEPROP 2 LAST $XR0 59 
J 0
(-4171 3800);
DISPLAY 0.638298 (-4171 3800);
PAINT MONO (-4171 3800);
FORCEPROP 2 LAST CDS_LIB mstr_standard
J 0
(-3950 3800);
DISPLAY 0.787234 (-3950 3800);
PAINT MONO (-3950 3800);
DISPLAY INVISIBLE (-3950 3800);
FORCEPROP 1 LAST OFFPAGE TRUE
J 0
(-3625 3675);
DISPLAY 0.936170 (-3625 3675);
PAINT GREEN (-3625 3675);
DISPLAY INVISIBLE (-3625 3675);
FORCEPROP 1 LAST COMMENT_BODY TRUE
J 0
(-3825 3700);
DISPLAY 0.936170 (-3825 3700);
PAINT GREEN (-3825 3700);
DISPLAY INVISIBLE (-3825 3700);
FORCEPROP 2 LAST PATH I138
J 0
(-3900 3875);
DISPLAY 0.787234 (-3900 3875);
PAINT MONO (-3900 3875);
DISPLAY INVISIBLE (-3900 3875);
FORCEADD OFFPAGE..6
(-3950 2800);
FORCEPROP 2 LAST $XR1 82 
J 0
(-4319 2800);
DISPLAY 0.638298 (-4319 2800);
PAINT MONO (-4319 2800);
FORCEPROP 2 LAST $XR0 59 
J 0
(-4229 2800);
DISPLAY 0.638298 (-4229 2800);
PAINT MONO (-4229 2800);
FORCEPROP 2 LAST CDS_LIB mstr_standard
J 0
(-3950 2800);
DISPLAY 0.787234 (-3950 2800);
PAINT MONO (-3950 2800);
DISPLAY INVISIBLE (-3950 2800);
FORCEPROP 1 LAST OFFPAGE TRUE
J 0
(-3625 2675);
DISPLAY 0.936170 (-3625 2675);
PAINT GREEN (-3625 2675);
DISPLAY INVISIBLE (-3625 2675);
FORCEPROP 1 LAST COMMENT_BODY TRUE
J 0
(-3850 2725);
DISPLAY 0.936170 (-3850 2725);
PAINT GREEN (-3850 2725);
DISPLAY INVISIBLE (-3850 2725);
FORCEPROP 2 LAST PATH I139
J 0
(-3900 2875);
DISPLAY 0.787234 (-3900 2875);
PAINT MONO (-3900 2875);
DISPLAY INVISIBLE (-3900 2875);
FORCEADD TAP..6
R 2
(650 4950);
FORCEPROP 3 LASTPIN (600 4950) SIG_NAME M_J_DQS_DP<15>
J 0
(610 4960);
DISPLAY 0.659574 (610 4960);
PAINT MONO (610 4960);
DISPLAY INVISIBLE (610 4960);
FORCEPROP 1 LASTPIN (600 4950) BN 15
J 2
(650 4960);
DISPLAY 0.617021 (650 4960);
PAINT PINK (650 4960);
FORCEPROP 2 LAST CDS_LIB mstr_standard
J 0
(650 4950);
DISPLAY 0.787234 (650 4950);
PAINT MONO (650 4950);
DISPLAY INVISIBLE (650 4950);
FORCEPROP 1 LAST BODY_TYPE PLUMBING
J 2
(650 4900);
DISPLAY 1.234043 (650 4900);
PAINT GREEN (650 4900);
DISPLAY INVISIBLE (650 4900);
FORCEPROP 1 LAST HDL_TAP TRUE
J 2
(325 4825);
DISPLAY 1.234043 (325 4825);
PAINT GREEN (325 4825);
DISPLAY INVISIBLE (325 4825);
FORCEPROP 1 LAST PATH I14
J 2
(650 4950);
DISPLAY 0.936170 (650 4950);
PAINT GREEN (650 4950);
DISPLAY INVISIBLE (650 4950);
FORCEADD TAP..6
(-3300 2700);
FORCEPROP 3 LASTPIN (-3250 2700) SIG_NAME M_J_ECC<7>
J 0
(-3240 2710);
DISPLAY 0.659574 (-3240 2710);
PAINT MONO (-3240 2710);
DISPLAY INVISIBLE (-3240 2710);
FORCEPROP 1 LASTPIN (-3250 2700) BN 7
J 0
(-3300 2710);
DISPLAY 0.617021 (-3300 2710);
PAINT PINK (-3300 2710);
FORCEPROP 2 LAST CDS_LIB mstr_standard
J 0
(-3300 2700);
DISPLAY 0.787234 (-3300 2700);
PAINT MONO (-3300 2700);
DISPLAY INVISIBLE (-3300 2700);
FORCEPROP 1 LAST BODY_TYPE PLUMBING
J 0
(-3300 2650);
DISPLAY 1.234043 (-3300 2650);
PAINT GREEN (-3300 2650);
DISPLAY INVISIBLE (-3300 2650);
FORCEPROP 1 LAST HDL_TAP TRUE
J 0
(-2975 2575);
DISPLAY 1.234043 (-2975 2575);
PAINT GREEN (-2975 2575);
DISPLAY INVISIBLE (-2975 2575);
FORCEPROP 1 LAST PATH I140
J 0
(-3300 2700);
DISPLAY 0.936170 (-3300 2700);
PAINT GREEN (-3300 2700);
DISPLAY INVISIBLE (-3300 2700);
FORCEADD TAP..6
(-3300 2650);
FORCEPROP 3 LASTPIN (-3250 2650) SIG_NAME M_J_ECC<4>
J 0
(-3240 2660);
DISPLAY 0.659574 (-3240 2660);
PAINT MONO (-3240 2660);
DISPLAY INVISIBLE (-3240 2660);
FORCEPROP 1 LASTPIN (-3250 2650) BN 4
J 0
(-3300 2660);
DISPLAY 0.617021 (-3300 2660);
PAINT PINK (-3300 2660);
FORCEPROP 2 LAST CDS_LIB mstr_standard
J 0
(-3300 2650);
DISPLAY 0.787234 (-3300 2650);
PAINT MONO (-3300 2650);
DISPLAY INVISIBLE (-3300 2650);
FORCEPROP 1 LAST BODY_TYPE PLUMBING
J 0
(-3300 2600);
DISPLAY 1.234043 (-3300 2600);
PAINT GREEN (-3300 2600);
DISPLAY INVISIBLE (-3300 2600);
FORCEPROP 1 LAST HDL_TAP TRUE
J 0
(-2975 2525);
DISPLAY 1.234043 (-2975 2525);
PAINT GREEN (-2975 2525);
DISPLAY INVISIBLE (-2975 2525);
FORCEPROP 1 LAST PATH I141
J 0
(-3300 2650);
DISPLAY 0.936170 (-3300 2650);
PAINT GREEN (-3300 2650);
DISPLAY INVISIBLE (-3300 2650);
FORCEADD TAP..6
(-3300 2600);
FORCEPROP 3 LASTPIN (-3250 2600) SIG_NAME M_J_ECC<5>
J 0
(-3240 2610);
DISPLAY 0.659574 (-3240 2610);
PAINT MONO (-3240 2610);
DISPLAY INVISIBLE (-3240 2610);
FORCEPROP 1 LASTPIN (-3250 2600) BN 5
J 0
(-3300 2610);
DISPLAY 0.617021 (-3300 2610);
PAINT PINK (-3300 2610);
FORCEPROP 2 LAST CDS_LIB mstr_standard
J 0
(-3300 2600);
DISPLAY 0.787234 (-3300 2600);
PAINT MONO (-3300 2600);
DISPLAY INVISIBLE (-3300 2600);
FORCEPROP 1 LAST BODY_TYPE PLUMBING
J 0
(-3300 2550);
DISPLAY 1.234043 (-3300 2550);
PAINT GREEN (-3300 2550);
DISPLAY INVISIBLE (-3300 2550);
FORCEPROP 1 LAST HDL_TAP TRUE
J 0
(-2975 2475);
DISPLAY 1.234043 (-2975 2475);
PAINT GREEN (-2975 2475);
DISPLAY INVISIBLE (-2975 2475);
FORCEPROP 1 LAST PATH I142
J 0
(-3300 2600);
DISPLAY 0.936170 (-3300 2600);
PAINT GREEN (-3300 2600);
DISPLAY INVISIBLE (-3300 2600);
FORCEADD TAP..6
(-3300 2550);
FORCEPROP 3 LASTPIN (-3250 2550) SIG_NAME M_J_ECC<2>
J 0
(-3240 2560);
DISPLAY 0.659574 (-3240 2560);
PAINT MONO (-3240 2560);
DISPLAY INVISIBLE (-3240 2560);
FORCEPROP 1 LASTPIN (-3250 2550) BN 2
J 0
(-3300 2560);
DISPLAY 0.617021 (-3300 2560);
PAINT PINK (-3300 2560);
FORCEPROP 2 LAST CDS_LIB mstr_standard
J 0
(-3300 2550);
DISPLAY 0.787234 (-3300 2550);
PAINT MONO (-3300 2550);
DISPLAY INVISIBLE (-3300 2550);
FORCEPROP 1 LAST BODY_TYPE PLUMBING
J 0
(-3300 2500);
DISPLAY 1.234043 (-3300 2500);
PAINT GREEN (-3300 2500);
DISPLAY INVISIBLE (-3300 2500);
FORCEPROP 1 LAST HDL_TAP TRUE
J 0
(-2975 2425);
DISPLAY 1.234043 (-2975 2425);
PAINT GREEN (-2975 2425);
DISPLAY INVISIBLE (-2975 2425);
FORCEPROP 1 LAST PATH I143
J 0
(-3300 2550);
DISPLAY 0.936170 (-3300 2550);
PAINT GREEN (-3300 2550);
DISPLAY INVISIBLE (-3300 2550);
FORCEADD TAP..6
(-3300 2500);
FORCEPROP 3 LASTPIN (-3250 2500) SIG_NAME M_J_ECC<3>
J 0
(-3240 2510);
DISPLAY 0.659574 (-3240 2510);
PAINT MONO (-3240 2510);
DISPLAY INVISIBLE (-3240 2510);
FORCEPROP 1 LASTPIN (-3250 2500) BN 3
J 0
(-3300 2510);
DISPLAY 0.617021 (-3300 2510);
PAINT PINK (-3300 2510);
FORCEPROP 2 LAST CDS_LIB mstr_standard
J 0
(-3300 2500);
DISPLAY 0.787234 (-3300 2500);
PAINT MONO (-3300 2500);
DISPLAY INVISIBLE (-3300 2500);
FORCEPROP 1 LAST BODY_TYPE PLUMBING
J 0
(-3300 2450);
DISPLAY 1.234043 (-3300 2450);
PAINT GREEN (-3300 2450);
DISPLAY INVISIBLE (-3300 2450);
FORCEPROP 1 LAST HDL_TAP TRUE
J 0
(-2975 2375);
DISPLAY 1.234043 (-2975 2375);
PAINT GREEN (-2975 2375);
DISPLAY INVISIBLE (-2975 2375);
FORCEPROP 1 LAST PATH I144
J 0
(-3300 2500);
DISPLAY 0.936170 (-3300 2500);
PAINT GREEN (-3300 2500);
DISPLAY INVISIBLE (-3300 2500);
FORCEADD TAP..6
(-3300 2400);
FORCEPROP 3 LASTPIN (-3250 2400) SIG_NAME M_J_ECC<1>
J 0
(-3240 2410);
DISPLAY 0.659574 (-3240 2410);
PAINT MONO (-3240 2410);
DISPLAY INVISIBLE (-3240 2410);
FORCEPROP 1 LASTPIN (-3250 2400) BN 1
J 0
(-3300 2410);
DISPLAY 0.617021 (-3300 2410);
PAINT PINK (-3300 2410);
FORCEPROP 2 LAST CDS_LIB mstr_standard
J 0
(-3300 2400);
DISPLAY 0.787234 (-3300 2400);
PAINT MONO (-3300 2400);
DISPLAY INVISIBLE (-3300 2400);
FORCEPROP 1 LAST BODY_TYPE PLUMBING
J 0
(-3300 2350);
DISPLAY 1.234043 (-3300 2350);
PAINT GREEN (-3300 2350);
DISPLAY INVISIBLE (-3300 2350);
FORCEPROP 1 LAST HDL_TAP TRUE
J 0
(-2975 2275);
DISPLAY 1.234043 (-2975 2275);
PAINT GREEN (-2975 2275);
DISPLAY INVISIBLE (-2975 2275);
FORCEPROP 1 LAST PATH I145
J 0
(-3300 2400);
DISPLAY 0.936170 (-3300 2400);
PAINT GREEN (-3300 2400);
DISPLAY INVISIBLE (-3300 2400);
FORCEADD TAP..6
(-3300 2450);
FORCEPROP 3 LASTPIN (-3250 2450) SIG_NAME M_J_ECC<0>
J 0
(-3240 2460);
DISPLAY 0.659574 (-3240 2460);
PAINT MONO (-3240 2460);
DISPLAY INVISIBLE (-3240 2460);
FORCEPROP 1 LASTPIN (-3250 2450) BN 0
J 0
(-3300 2460);
DISPLAY 0.617021 (-3300 2460);
PAINT PINK (-3300 2460);
FORCEPROP 2 LAST CDS_LIB mstr_standard
J 0
(-3300 2450);
DISPLAY 0.787234 (-3300 2450);
PAINT MONO (-3300 2450);
DISPLAY INVISIBLE (-3300 2450);
FORCEPROP 1 LAST BODY_TYPE PLUMBING
J 0
(-3300 2400);
DISPLAY 1.234043 (-3300 2400);
PAINT GREEN (-3300 2400);
DISPLAY INVISIBLE (-3300 2400);
FORCEPROP 1 LAST HDL_TAP TRUE
J 0
(-2975 2325);
DISPLAY 1.234043 (-2975 2325);
PAINT GREEN (-2975 2325);
DISPLAY INVISIBLE (-2975 2325);
FORCEPROP 1 LAST PATH I146
J 0
(-3300 2450);
DISPLAY 0.936170 (-3300 2450);
PAINT GREEN (-3300 2450);
DISPLAY INVISIBLE (-3300 2450);
FORCEADD OFFPAGE..1
(-3950 2750);
FORCEPROP 2 LAST $XR1 82 
J 0
(-4291 2750);
DISPLAY 0.638298 (-4291 2750);
PAINT MONO (-4291 2750);
FORCEPROP 2 LAST $XR0 59 
J 0
(-4201 2750);
DISPLAY 0.638298 (-4201 2750);
PAINT MONO (-4201 2750);
FORCEPROP 2 LAST CDS_LIB mstr_standard
J 0
(-3950 2750);
DISPLAY 0.787234 (-3950 2750);
PAINT MONO (-3950 2750);
DISPLAY INVISIBLE (-3950 2750);
FORCEPROP 1 LAST OFFPAGE TRUE
J 0
(-3625 2625);
DISPLAY 0.936170 (-3625 2625);
PAINT GREEN (-3625 2625);
DISPLAY INVISIBLE (-3625 2625);
FORCEPROP 1 LAST COMMENT_BODY TRUE
J 0
(-3825 2650);
DISPLAY 0.936170 (-3825 2650);
PAINT GREEN (-3825 2650);
DISPLAY INVISIBLE (-3825 2650);
FORCEPROP 2 LAST PATH I147
J 0
(-3900 2825);
DISPLAY 0.787234 (-3900 2825);
PAINT MONO (-3900 2825);
DISPLAY INVISIBLE (-3900 2825);
FORCEADD OFFPAGE..1
(-3950 2700);
FORCEPROP 2 LAST $XR5 82 
J 0
(-4621 2700);
DISPLAY 0.638298 (-4621 2700);
PAINT MONO (-4621 2700);
FORCEPROP 2 LAST $XR4 80 
J 0
(-4531 2700);
DISPLAY 0.638298 (-4531 2700);
PAINT MONO (-4531 2700);
FORCEPROP 2 LAST $XR3 79 
J 0
(-4441 2700);
DISPLAY 0.638298 (-4441 2700);
PAINT MONO (-4441 2700);
FORCEPROP 2 LAST $XR2 78 
J 0
(-4351 2700);
DISPLAY 0.638298 (-4351 2700);
PAINT MONO (-4351 2700);
FORCEPROP 2 LAST $XR1 77 
J 0
(-4261 2700);
DISPLAY 0.638298 (-4261 2700);
PAINT MONO (-4261 2700);
FORCEPROP 2 LAST $XR0 55 
J 0
(-4171 2700);
DISPLAY 0.638298 (-4171 2700);
PAINT MONO (-4171 2700);
FORCEPROP 2 LAST CDS_LIB mstr_standard
J 0
(-3950 2700);
DISPLAY 0.787234 (-3950 2700);
PAINT MONO (-3950 2700);
DISPLAY INVISIBLE (-3950 2700);
FORCEPROP 1 LAST OFFPAGE TRUE
J 0
(-3625 2575);
DISPLAY 0.936170 (-3625 2575);
PAINT GREEN (-3625 2575);
DISPLAY INVISIBLE (-3625 2575);
FORCEPROP 1 LAST COMMENT_BODY TRUE
J 0
(-3825 2600);
DISPLAY 0.936170 (-3825 2600);
PAINT GREEN (-3825 2600);
DISPLAY INVISIBLE (-3825 2600);
FORCEPROP 2 LAST PATH I148
J 0
(-3900 2775);
DISPLAY 0.787234 (-3900 2775);
PAINT MONO (-3900 2775);
DISPLAY INVISIBLE (-3900 2775);
FORCEADD OFFPAGE..1
(-4100 2100);
FORCEPROP 2 LAST $XR1 82 
J 0
(-4471 2100);
DISPLAY 0.638298 (-4471 2100);
PAINT MONO (-4471 2100);
FORCEPROP 2 LAST $XR0 59 
J 0
(-4381 2100);
DISPLAY 0.638298 (-4381 2100);
PAINT MONO (-4381 2100);
FORCEPROP 2 LAST CDS_LIB mstr_standard
J 0
(-4100 2100);
DISPLAY 0.787234 (-4100 2100);
PAINT MONO (-4100 2100);
DISPLAY INVISIBLE (-4100 2100);
FORCEPROP 1 LAST OFFPAGE TRUE
J 0
(-3775 1975);
DISPLAY 0.936170 (-3775 1975);
PAINT GREEN (-3775 1975);
DISPLAY INVISIBLE (-3775 1975);
FORCEPROP 1 LAST COMMENT_BODY TRUE
J 0
(-3975 2000);
DISPLAY 0.936170 (-3975 2000);
PAINT GREEN (-3975 2000);
DISPLAY INVISIBLE (-3975 2000);
FORCEPROP 2 LAST PATH I149
J 0
(-4050 2175);
DISPLAY 0.787234 (-4050 2175);
PAINT MONO (-4050 2175);
DISPLAY INVISIBLE (-4050 2175);
FORCEADD TAP..6
R 2
(650 4650);
FORCEPROP 3 LASTPIN (600 4650) SIG_NAME M_J_DQS_DP<12>
J 0
(610 4660);
DISPLAY 0.659574 (610 4660);
PAINT MONO (610 4660);
DISPLAY INVISIBLE (610 4660);
FORCEPROP 1 LASTPIN (600 4650) BN 12
J 2
(650 4660);
DISPLAY 0.617021 (650 4660);
PAINT PINK (650 4660);
FORCEPROP 2 LAST CDS_LIB mstr_standard
J 0
(650 4650);
DISPLAY 0.787234 (650 4650);
PAINT MONO (650 4650);
DISPLAY INVISIBLE (650 4650);
FORCEPROP 1 LAST BODY_TYPE PLUMBING
J 2
(650 4600);
DISPLAY 1.234043 (650 4600);
PAINT GREEN (650 4600);
DISPLAY INVISIBLE (650 4600);
FORCEPROP 1 LAST HDL_TAP TRUE
J 2
(325 4525);
DISPLAY 1.234043 (325 4525);
PAINT GREEN (325 4525);
DISPLAY INVISIBLE (325 4525);
FORCEPROP 1 LAST PATH I15
J 2
(650 4650);
DISPLAY 0.936170 (650 4650);
PAINT GREEN (650 4650);
DISPLAY INVISIBLE (650 4650);
FORCEADD OFFPAGE..5
(-4125 2150);
FORCEPROP 2 LAST $XR1 59 
J 0
(-4469 2150);
DISPLAY 0.638298 (-4469 2150);
PAINT MONO (-4469 2150);
FORCEPROP 2 LAST $XR0 82 
J 0
(-4379 2150);
DISPLAY 0.638298 (-4379 2150);
PAINT MONO (-4379 2150);
FORCEPROP 2 LAST CDS_LIB mstr_standard
J 0
(-4125 2150);
DISPLAY 0.787234 (-4125 2150);
PAINT MONO (-4125 2150);
DISPLAY INVISIBLE (-4125 2150);
FORCEPROP 1 LAST OFFPAGE TRUE
J 0
(-3800 2025);
DISPLAY 1.404255 (-3800 2025);
PAINT GREEN (-3800 2025);
DISPLAY INVISIBLE (-3800 2025);
FORCEPROP 1 LAST COMMENT_BODY TRUE
J 0
(-4025 2075);
DISPLAY 1.404255 (-4025 2075);
PAINT GREEN (-4025 2075);
DISPLAY INVISIBLE (-4025 2075);
FORCEPROP 2 LAST PATH I150
J 0
(-4075 2225);
DISPLAY 0.787234 (-4075 2225);
PAINT MONO (-4075 2225);
DISPLAY INVISIBLE (-4075 2225);
FORCEADD TAP..6
(-3600 3600);
FORCEPROP 3 LASTPIN (-3550 3600) SIG_NAME M_J_CLK_DP<1>
J 0
(-3540 3610);
DISPLAY 0.659574 (-3540 3610);
PAINT MONO (-3540 3610);
DISPLAY INVISIBLE (-3540 3610);
FORCEPROP 1 LASTPIN (-3550 3600) BN 1
J 0
(-3600 3610);
DISPLAY 0.617021 (-3600 3610);
PAINT PINK (-3600 3610);
FORCEPROP 2 LAST CDS_LIB mstr_standard
J 0
(-3600 3600);
DISPLAY 0.787234 (-3600 3600);
PAINT MONO (-3600 3600);
DISPLAY INVISIBLE (-3600 3600);
FORCEPROP 1 LAST BODY_TYPE PLUMBING
J 0
(-3600 3550);
DISPLAY 1.234043 (-3600 3550);
PAINT GREEN (-3600 3550);
DISPLAY INVISIBLE (-3600 3550);
FORCEPROP 1 LAST HDL_TAP TRUE
J 0
(-3275 3475);
DISPLAY 1.234043 (-3275 3475);
PAINT GREEN (-3275 3475);
DISPLAY INVISIBLE (-3275 3475);
FORCEPROP 1 LAST PATH I152
J 0
(-3600 3600);
DISPLAY 0.936170 (-3600 3600);
PAINT GREEN (-3600 3600);
DISPLAY INVISIBLE (-3600 3600);
FORCEADD TAP..6
(-3600 3500);
FORCEPROP 3 LASTPIN (-3550 3500) SIG_NAME M_J_CLK_DP<0>
J 0
(-3540 3510);
DISPLAY 0.659574 (-3540 3510);
PAINT MONO (-3540 3510);
DISPLAY INVISIBLE (-3540 3510);
FORCEPROP 1 LASTPIN (-3550 3500) BN 0
J 0
(-3600 3510);
DISPLAY 0.617021 (-3600 3510);
PAINT PINK (-3600 3510);
FORCEPROP 2 LAST CDS_LIB mstr_standard
J 0
(-3600 3500);
DISPLAY 0.787234 (-3600 3500);
PAINT MONO (-3600 3500);
DISPLAY INVISIBLE (-3600 3500);
FORCEPROP 1 LAST BODY_TYPE PLUMBING
J 0
(-3600 3450);
DISPLAY 1.234043 (-3600 3450);
PAINT GREEN (-3600 3450);
DISPLAY INVISIBLE (-3600 3450);
FORCEPROP 1 LAST HDL_TAP TRUE
J 0
(-3275 3375);
DISPLAY 1.234043 (-3275 3375);
PAINT GREEN (-3275 3375);
DISPLAY INVISIBLE (-3275 3375);
FORCEPROP 1 LAST PATH I153
J 0
(-3600 3500);
DISPLAY 0.936170 (-3600 3500);
PAINT GREEN (-3600 3500);
DISPLAY INVISIBLE (-3600 3500);
FORCEADD TAP..6
(-3750 3550);
FORCEPROP 3 LASTPIN (-3700 3550) SIG_NAME M_J_CLK_DN<1>
J 0
(-3690 3560);
DISPLAY 0.659574 (-3690 3560);
PAINT MONO (-3690 3560);
DISPLAY INVISIBLE (-3690 3560);
FORCEPROP 1 LASTPIN (-3700 3550) BN 1
J 0
(-3750 3560);
DISPLAY 0.617021 (-3750 3560);
PAINT PINK (-3750 3560);
FORCEPROP 2 LAST CDS_LIB mstr_standard
J 0
(-3750 3550);
DISPLAY 0.787234 (-3750 3550);
PAINT MONO (-3750 3550);
DISPLAY INVISIBLE (-3750 3550);
FORCEPROP 1 LAST BODY_TYPE PLUMBING
J 0
(-3750 3500);
DISPLAY 1.234043 (-3750 3500);
PAINT GREEN (-3750 3500);
DISPLAY INVISIBLE (-3750 3500);
FORCEPROP 1 LAST HDL_TAP TRUE
J 0
(-3425 3425);
DISPLAY 1.234043 (-3425 3425);
PAINT GREEN (-3425 3425);
DISPLAY INVISIBLE (-3425 3425);
FORCEPROP 1 LAST PATH I154
J 0
(-3750 3550);
DISPLAY 0.936170 (-3750 3550);
PAINT GREEN (-3750 3550);
DISPLAY INVISIBLE (-3750 3550);
FORCEADD TAP..6
(-3750 3450);
FORCEPROP 3 LASTPIN (-3700 3450) SIG_NAME M_J_CLK_DN<0>
J 0
(-3690 3460);
DISPLAY 0.659574 (-3690 3460);
PAINT MONO (-3690 3460);
DISPLAY INVISIBLE (-3690 3460);
FORCEPROP 1 LASTPIN (-3700 3450) BN 0
J 0
(-3750 3460);
DISPLAY 0.617021 (-3750 3460);
PAINT PINK (-3750 3460);
FORCEPROP 2 LAST CDS_LIB mstr_standard
J 0
(-3750 3450);
DISPLAY 0.787234 (-3750 3450);
PAINT MONO (-3750 3450);
DISPLAY INVISIBLE (-3750 3450);
FORCEPROP 1 LAST BODY_TYPE PLUMBING
J 0
(-3750 3400);
DISPLAY 1.234043 (-3750 3400);
PAINT GREEN (-3750 3400);
DISPLAY INVISIBLE (-3750 3400);
FORCEPROP 1 LAST HDL_TAP TRUE
J 0
(-3425 3325);
DISPLAY 1.234043 (-3425 3325);
PAINT GREEN (-3425 3325);
DISPLAY INVISIBLE (-3425 3325);
FORCEPROP 1 LAST PATH I155
J 0
(-3750 3450);
DISPLAY 0.936170 (-3750 3450);
PAINT GREEN (-3750 3450);
DISPLAY INVISIBLE (-3750 3450);
FORCEADD OFFPAGE..1
(-4300 3600);
FORCEPROP 2 LAST $XR1 82 
J 0
(-4611 3600);
DISPLAY 0.638298 (-4611 3600);
PAINT MONO (-4611 3600);
FORCEPROP 2 LAST $XR0 59 
J 0
(-4521 3600);
DISPLAY 0.638298 (-4521 3600);
PAINT MONO (-4521 3600);
FORCEPROP 2 LAST CDS_LIB mstr_standard
J 0
(-4300 3600);
DISPLAY 0.787234 (-4300 3600);
PAINT MONO (-4300 3600);
DISPLAY INVISIBLE (-4300 3600);
FORCEPROP 1 LAST OFFPAGE TRUE
J 0
(-3975 3475);
DISPLAY 0.936170 (-3975 3475);
PAINT GREEN (-3975 3475);
DISPLAY INVISIBLE (-3975 3475);
FORCEPROP 1 LAST COMMENT_BODY TRUE
J 0
(-4175 3500);
DISPLAY 0.936170 (-4175 3500);
PAINT GREEN (-4175 3500);
DISPLAY INVISIBLE (-4175 3500);
FORCEPROP 2 LAST PATH I156
J 0
(-4250 3675);
DISPLAY 0.787234 (-4250 3675);
PAINT MONO (-4250 3675);
DISPLAY INVISIBLE (-4250 3675);
FORCEADD OFFPAGE..1
(-4300 3650);
FORCEPROP 2 LAST $XR1 82 
J 0
(-4611 3650);
DISPLAY 0.638298 (-4611 3650);
PAINT MONO (-4611 3650);
FORCEPROP 2 LAST $XR0 59 
J 0
(-4521 3650);
DISPLAY 0.638298 (-4521 3650);
PAINT MONO (-4521 3650);
FORCEPROP 2 LAST CDS_LIB mstr_standard
J 0
(-4300 3650);
DISPLAY 0.787234 (-4300 3650);
PAINT MONO (-4300 3650);
DISPLAY INVISIBLE (-4300 3650);
FORCEPROP 1 LAST OFFPAGE TRUE
J 0
(-3975 3525);
DISPLAY 0.936170 (-3975 3525);
PAINT GREEN (-3975 3525);
DISPLAY INVISIBLE (-3975 3525);
FORCEPROP 1 LAST COMMENT_BODY TRUE
J 0
(-4175 3550);
DISPLAY 0.936170 (-4175 3550);
PAINT GREEN (-4175 3550);
DISPLAY INVISIBLE (-4175 3550);
FORCEPROP 2 LAST PATH I157
J 0
(-4250 3725);
DISPLAY 0.787234 (-4250 3725);
PAINT MONO (-4250 3725);
DISPLAY INVISIBLE (-4250 3725);
FORCEADD TAP..6
(-3300 3300);
FORCEPROP 3 LASTPIN (-3250 3300) SIG_NAME M_J_CS_N<3>
J 0
(-3240 3310);
DISPLAY 0.659574 (-3240 3310);
PAINT MONO (-3240 3310);
DISPLAY INVISIBLE (-3240 3310);
FORCEPROP 1 LASTPIN (-3250 3300) BN 3
J 0
(-3300 3310);
DISPLAY 0.617021 (-3300 3310);
PAINT PINK (-3300 3310);
FORCEPROP 2 LAST CDS_LIB mstr_standard
J 0
(-3300 3300);
DISPLAY 0.787234 (-3300 3300);
PAINT MONO (-3300 3300);
DISPLAY INVISIBLE (-3300 3300);
FORCEPROP 1 LAST BODY_TYPE PLUMBING
J 0
(-3300 3250);
DISPLAY 1.234043 (-3300 3250);
PAINT GREEN (-3300 3250);
DISPLAY INVISIBLE (-3300 3250);
FORCEPROP 1 LAST HDL_TAP TRUE
J 0
(-2975 3175);
DISPLAY 1.234043 (-2975 3175);
PAINT GREEN (-2975 3175);
DISPLAY INVISIBLE (-2975 3175);
FORCEPROP 1 LAST PATH I158
J 0
(-3300 3300);
DISPLAY 0.936170 (-3300 3300);
PAINT GREEN (-3300 3300);
DISPLAY INVISIBLE (-3300 3300);
FORCEADD TAP..6
(-3300 3250);
FORCEPROP 3 LASTPIN (-3250 3250) SIG_NAME M_J_CS_N<2>
J 0
(-3240 3260);
DISPLAY 0.659574 (-3240 3260);
PAINT MONO (-3240 3260);
DISPLAY INVISIBLE (-3240 3260);
FORCEPROP 1 LASTPIN (-3250 3250) BN 2
J 0
(-3300 3260);
DISPLAY 0.617021 (-3300 3260);
PAINT PINK (-3300 3260);
FORCEPROP 2 LAST CDS_LIB mstr_standard
J 0
(-3300 3250);
DISPLAY 0.787234 (-3300 3250);
PAINT MONO (-3300 3250);
DISPLAY INVISIBLE (-3300 3250);
FORCEPROP 1 LAST BODY_TYPE PLUMBING
J 0
(-3300 3200);
DISPLAY 1.234043 (-3300 3200);
PAINT GREEN (-3300 3200);
DISPLAY INVISIBLE (-3300 3200);
FORCEPROP 1 LAST HDL_TAP TRUE
J 0
(-2975 3125);
DISPLAY 1.234043 (-2975 3125);
PAINT GREEN (-2975 3125);
DISPLAY INVISIBLE (-2975 3125);
FORCEPROP 1 LAST PATH I159
J 0
(-3300 3250);
DISPLAY 0.936170 (-3300 3250);
PAINT GREEN (-3300 3250);
DISPLAY INVISIBLE (-3300 3250);
FORCEADD TAP..6
R 2
(650 4550);
FORCEPROP 3 LASTPIN (600 4550) SIG_NAME M_J_DQS_DP<11>
J 0
(610 4560);
DISPLAY 0.659574 (610 4560);
PAINT MONO (610 4560);
DISPLAY INVISIBLE (610 4560);
FORCEPROP 1 LASTPIN (600 4550) BN 11
J 2
(650 4560);
DISPLAY 0.617021 (650 4560);
PAINT PINK (650 4560);
FORCEPROP 2 LAST CDS_LIB mstr_standard
J 0
(650 4550);
DISPLAY 0.787234 (650 4550);
PAINT MONO (650 4550);
DISPLAY INVISIBLE (650 4550);
FORCEPROP 1 LAST BODY_TYPE PLUMBING
J 2
(650 4500);
DISPLAY 1.234043 (650 4500);
PAINT GREEN (650 4500);
DISPLAY INVISIBLE (650 4500);
FORCEPROP 1 LAST HDL_TAP TRUE
J 2
(325 4425);
DISPLAY 1.234043 (325 4425);
PAINT GREEN (325 4425);
DISPLAY INVISIBLE (325 4425);
FORCEPROP 1 LAST PATH I16
J 2
(650 4550);
DISPLAY 0.936170 (650 4550);
PAINT GREEN (650 4550);
DISPLAY INVISIBLE (650 4550);
FORCEADD TAP..6
(-3300 3200);
FORCEPROP 3 LASTPIN (-3250 3200) SIG_NAME M_J_CS_N<1>
J 0
(-3240 3210);
DISPLAY 0.659574 (-3240 3210);
PAINT MONO (-3240 3210);
DISPLAY INVISIBLE (-3240 3210);
FORCEPROP 1 LASTPIN (-3250 3200) BN 1
J 0
(-3300 3210);
DISPLAY 0.617021 (-3300 3210);
PAINT PINK (-3300 3210);
FORCEPROP 2 LAST CDS_LIB mstr_standard
J 0
(-3300 3200);
DISPLAY 0.787234 (-3300 3200);
PAINT MONO (-3300 3200);
DISPLAY INVISIBLE (-3300 3200);
FORCEPROP 1 LAST BODY_TYPE PLUMBING
J 0
(-3300 3150);
DISPLAY 1.234043 (-3300 3150);
PAINT GREEN (-3300 3150);
DISPLAY INVISIBLE (-3300 3150);
FORCEPROP 1 LAST HDL_TAP TRUE
J 0
(-2975 3075);
DISPLAY 1.234043 (-2975 3075);
PAINT GREEN (-2975 3075);
DISPLAY INVISIBLE (-2975 3075);
FORCEPROP 1 LAST PATH I160
J 0
(-3300 3200);
DISPLAY 0.936170 (-3300 3200);
PAINT GREEN (-3300 3200);
DISPLAY INVISIBLE (-3300 3200);
FORCEADD TAP..6
(-3300 3150);
FORCEPROP 3 LASTPIN (-3250 3150) SIG_NAME M_J_CS_N<0>
J 0
(-3240 3160);
DISPLAY 0.659574 (-3240 3160);
PAINT MONO (-3240 3160);
DISPLAY INVISIBLE (-3240 3160);
FORCEPROP 1 LASTPIN (-3250 3150) BN 0
J 0
(-3300 3160);
DISPLAY 0.617021 (-3300 3160);
PAINT PINK (-3300 3160);
FORCEPROP 2 LAST CDS_LIB mstr_standard
J 0
(-3300 3150);
DISPLAY 0.787234 (-3300 3150);
PAINT MONO (-3300 3150);
DISPLAY INVISIBLE (-3300 3150);
FORCEPROP 1 LAST BODY_TYPE PLUMBING
J 0
(-3300 3100);
DISPLAY 1.234043 (-3300 3100);
PAINT GREEN (-3300 3100);
DISPLAY INVISIBLE (-3300 3100);
FORCEPROP 1 LAST HDL_TAP TRUE
J 0
(-2975 3025);
DISPLAY 1.234043 (-2975 3025);
PAINT GREEN (-2975 3025);
DISPLAY INVISIBLE (-2975 3025);
FORCEPROP 1 LAST PATH I161
J 0
(-3300 3150);
DISPLAY 0.936170 (-3300 3150);
PAINT GREEN (-3300 3150);
DISPLAY INVISIBLE (-3300 3150);
FORCEADD TAP..6
(-3300 3050);
FORCEPROP 3 LASTPIN (-3250 3050) SIG_NAME M_J_CKE<1>
J 0
(-3240 3060);
DISPLAY 0.659574 (-3240 3060);
PAINT MONO (-3240 3060);
DISPLAY INVISIBLE (-3240 3060);
FORCEPROP 1 LASTPIN (-3250 3050) BN 1
J 0
(-3300 3060);
DISPLAY 0.617021 (-3300 3060);
PAINT PINK (-3300 3060);
FORCEPROP 2 LAST CDS_LIB mstr_standard
J 0
(-3300 3050);
DISPLAY 0.787234 (-3300 3050);
PAINT MONO (-3300 3050);
DISPLAY INVISIBLE (-3300 3050);
FORCEPROP 1 LAST BODY_TYPE PLUMBING
J 0
(-3300 3000);
DISPLAY 1.234043 (-3300 3000);
PAINT GREEN (-3300 3000);
DISPLAY INVISIBLE (-3300 3000);
FORCEPROP 1 LAST HDL_TAP TRUE
J 0
(-2975 2925);
DISPLAY 1.234043 (-2975 2925);
PAINT GREEN (-2975 2925);
DISPLAY INVISIBLE (-2975 2925);
FORCEPROP 1 LAST PATH I162
J 0
(-3300 3050);
DISPLAY 0.936170 (-3300 3050);
PAINT GREEN (-3300 3050);
DISPLAY INVISIBLE (-3300 3050);
FORCEADD TAP..6
(-3300 3000);
FORCEPROP 3 LASTPIN (-3250 3000) SIG_NAME M_J_CKE<0>
J 0
(-3240 3010);
DISPLAY 0.659574 (-3240 3010);
PAINT MONO (-3240 3010);
DISPLAY INVISIBLE (-3240 3010);
FORCEPROP 1 LASTPIN (-3250 3000) BN 0
J 0
(-3300 3010);
DISPLAY 0.617021 (-3300 3010);
PAINT PINK (-3300 3010);
FORCEPROP 2 LAST CDS_LIB mstr_standard
J 0
(-3300 3000);
DISPLAY 0.787234 (-3300 3000);
PAINT MONO (-3300 3000);
DISPLAY INVISIBLE (-3300 3000);
FORCEPROP 1 LAST BODY_TYPE PLUMBING
J 0
(-3300 2950);
DISPLAY 1.234043 (-3300 2950);
PAINT GREEN (-3300 2950);
DISPLAY INVISIBLE (-3300 2950);
FORCEPROP 1 LAST HDL_TAP TRUE
J 0
(-2975 2875);
DISPLAY 1.234043 (-2975 2875);
PAINT GREEN (-2975 2875);
DISPLAY INVISIBLE (-2975 2875);
FORCEPROP 1 LAST PATH I163
J 0
(-3300 3000);
DISPLAY 0.936170 (-3300 3000);
PAINT GREEN (-3300 3000);
DISPLAY INVISIBLE (-3300 3000);
FORCEADD TAP..6
(-3300 2900);
FORCEPROP 3 LASTPIN (-3250 2900) SIG_NAME M_J_ODT<1>
J 0
(-3240 2910);
DISPLAY 0.659574 (-3240 2910);
PAINT MONO (-3240 2910);
DISPLAY INVISIBLE (-3240 2910);
FORCEPROP 1 LASTPIN (-3250 2900) BN 1
J 0
(-3300 2910);
DISPLAY 0.617021 (-3300 2910);
PAINT PINK (-3300 2910);
FORCEPROP 2 LAST CDS_LIB mstr_standard
J 0
(-3300 2900);
DISPLAY 0.787234 (-3300 2900);
PAINT MONO (-3300 2900);
DISPLAY INVISIBLE (-3300 2900);
FORCEPROP 1 LAST BODY_TYPE PLUMBING
J 0
(-3300 2850);
DISPLAY 1.234043 (-3300 2850);
PAINT GREEN (-3300 2850);
DISPLAY INVISIBLE (-3300 2850);
FORCEPROP 1 LAST HDL_TAP TRUE
J 0
(-2975 2775);
DISPLAY 1.234043 (-2975 2775);
PAINT GREEN (-2975 2775);
DISPLAY INVISIBLE (-2975 2775);
FORCEPROP 1 LAST PATH I164
J 0
(-3300 2900);
DISPLAY 0.936170 (-3300 2900);
PAINT GREEN (-3300 2900);
DISPLAY INVISIBLE (-3300 2900);
FORCEADD OFFPAGE..1
(-3950 3350);
FORCEPROP 2 LAST $XR1 82 
J 0
(-4261 3350);
DISPLAY 0.638298 (-4261 3350);
PAINT MONO (-4261 3350);
FORCEPROP 2 LAST $XR0 59 
J 0
(-4171 3350);
DISPLAY 0.638298 (-4171 3350);
PAINT MONO (-4171 3350);
FORCEPROP 2 LAST CDS_LIB mstr_standard
J 0
(-3950 3350);
DISPLAY 0.787234 (-3950 3350);
PAINT MONO (-3950 3350);
DISPLAY INVISIBLE (-3950 3350);
FORCEPROP 1 LAST OFFPAGE TRUE
J 0
(-3625 3225);
DISPLAY 0.936170 (-3625 3225);
PAINT GREEN (-3625 3225);
DISPLAY INVISIBLE (-3625 3225);
FORCEPROP 1 LAST COMMENT_BODY TRUE
J 0
(-3825 3250);
DISPLAY 0.936170 (-3825 3250);
PAINT GREEN (-3825 3250);
DISPLAY INVISIBLE (-3825 3250);
FORCEPROP 2 LAST PATH I165
J 0
(-3900 3425);
DISPLAY 0.787234 (-3900 3425);
PAINT MONO (-3900 3425);
DISPLAY INVISIBLE (-3900 3425);
FORCEADD OFFPAGE..1
(-3950 3100);
FORCEPROP 2 LAST $XR1 82 
J 0
(-4261 3100);
DISPLAY 0.638298 (-4261 3100);
PAINT MONO (-4261 3100);
FORCEPROP 2 LAST $XR0 59 
J 0
(-4171 3100);
DISPLAY 0.638298 (-4171 3100);
PAINT MONO (-4171 3100);
FORCEPROP 2 LAST CDS_LIB mstr_standard
J 0
(-3950 3100);
DISPLAY 0.787234 (-3950 3100);
PAINT MONO (-3950 3100);
DISPLAY INVISIBLE (-3950 3100);
FORCEPROP 1 LAST OFFPAGE TRUE
J 0
(-3625 2975);
DISPLAY 0.936170 (-3625 2975);
PAINT GREEN (-3625 2975);
DISPLAY INVISIBLE (-3625 2975);
FORCEPROP 1 LAST COMMENT_BODY TRUE
J 0
(-3825 3000);
DISPLAY 0.936170 (-3825 3000);
PAINT GREEN (-3825 3000);
DISPLAY INVISIBLE (-3825 3000);
FORCEPROP 2 LAST PATH I166
J 0
(-3900 3175);
DISPLAY 0.787234 (-3900 3175);
PAINT MONO (-3900 3175);
DISPLAY INVISIBLE (-3900 3175);
FORCEADD OFFPAGE..1
(-3950 2950);
FORCEPROP 2 LAST $XR1 82 
J 0
(-4261 2950);
DISPLAY 0.638298 (-4261 2950);
PAINT MONO (-4261 2950);
FORCEPROP 2 LAST $XR0 59 
J 0
(-4171 2950);
DISPLAY 0.638298 (-4171 2950);
PAINT MONO (-4171 2950);
FORCEPROP 2 LAST CDS_LIB mstr_standard
J 0
(-3950 2950);
DISPLAY 0.787234 (-3950 2950);
PAINT MONO (-3950 2950);
DISPLAY INVISIBLE (-3950 2950);
FORCEPROP 1 LAST OFFPAGE TRUE
J 0
(-3625 2825);
DISPLAY 0.936170 (-3625 2825);
PAINT GREEN (-3625 2825);
DISPLAY INVISIBLE (-3625 2825);
FORCEPROP 1 LAST COMMENT_BODY TRUE
J 0
(-3825 2850);
DISPLAY 0.936170 (-3825 2850);
PAINT GREEN (-3825 2850);
DISPLAY INVISIBLE (-3825 2850);
FORCEPROP 2 LAST PATH I167
J 0
(-3900 3025);
DISPLAY 0.787234 (-3900 3025);
PAINT MONO (-3900 3025);
DISPLAY INVISIBLE (-3900 3025);
FORCEADD TAP..6
(-3300 2850);
FORCEPROP 3 LASTPIN (-3250 2850) SIG_NAME M_J_ODT<0>
J 0
(-3240 2860);
DISPLAY 0.659574 (-3240 2860);
PAINT MONO (-3240 2860);
DISPLAY INVISIBLE (-3240 2860);
FORCEPROP 1 LASTPIN (-3250 2850) BN 0
J 0
(-3300 2860);
DISPLAY 0.617021 (-3300 2860);
PAINT PINK (-3300 2860);
FORCEPROP 2 LAST CDS_LIB mstr_standard
J 0
(-3300 2850);
DISPLAY 0.787234 (-3300 2850);
PAINT MONO (-3300 2850);
DISPLAY INVISIBLE (-3300 2850);
FORCEPROP 1 LAST BODY_TYPE PLUMBING
J 0
(-3300 2800);
DISPLAY 1.234043 (-3300 2800);
PAINT GREEN (-3300 2800);
DISPLAY INVISIBLE (-3300 2800);
FORCEPROP 1 LAST HDL_TAP TRUE
J 0
(-2975 2725);
DISPLAY 1.234043 (-2975 2725);
PAINT GREEN (-2975 2725);
DISPLAY INVISIBLE (-2975 2725);
FORCEPROP 1 LAST PATH I168
J 0
(-3300 2850);
DISPLAY 0.936170 (-3300 2850);
PAINT GREEN (-3300 2850);
DISPLAY INVISIBLE (-3300 2850);
FORCEADD SCONN288_H44441004..4
(-350 2000);
FORCEPROP 1 LAST LOCATION J1G3
J 0
(-800 3100);
DISPLAY 0.617021 (-800 3100);
PAINT AQUA (-800 3100);
FORCEPROP 1 LAST PART_NUMBER H44441-004
J 0
(-800 950);
DISPLAY 0.617021 (-800 950);
PAINT BLUE (-800 950);
FORCEPROP 1 LAST MATERIAL SCONN
J 0
(-800 3050);
DISPLAY 0.617021 (-800 3050);
PAINT SKYBLUE (-800 3050);
FORCEPROP 2 LASTPIN (-850 2550) $PN 77
J 2
(-860 2560);
DISPLAY 0.617021 (-860 2560);
PAINT ORANGE (-860 2560);
FORCEPROP 2 LASTPIN (-850 2500) $PN 221
J 2
(-860 2510);
DISPLAY 0.617021 (-860 2510);
PAINT ORANGE (-860 2510);
FORCEPROP 2 LASTPIN (-850 2850) $PN 142
J 2
(-860 2860);
DISPLAY 0.617021 (-860 2860);
PAINT ORANGE (-860 2860);
FORCEPROP 2 LASTPIN (-850 2800) $PN 143
J 2
(-860 2810);
DISPLAY 0.617021 (-860 2810);
PAINT ORANGE (-860 2810);
FORCEPROP 2 LASTPIN (-850 2750) $PN 288
J 2
(-860 2760);
DISPLAY 0.617021 (-860 2760);
PAINT ORANGE (-860 2760);
FORCEPROP 2 LASTPIN (-850 2700) $PN 286
J 2
(-860 2710);
DISPLAY 0.617021 (-860 2710);
PAINT ORANGE (-860 2710);
FORCEPROP 2 LASTPIN (-850 2650) $PN 287
J 2
(-860 2660);
DISPLAY 0.617021 (-860 2660);
PAINT ORANGE (-860 2660);
FORCEPROP 2 LASTPIN (-850 2400) $PN 59
J 2
(-860 2410);
DISPLAY 0.617021 (-860 2410);
PAINT ORANGE (-860 2410);
FORCEPROP 2 LASTPIN (-850 2350) $PN 61
J 2
(-860 2360);
DISPLAY 0.617021 (-860 2360);
PAINT ORANGE (-860 2360);
FORCEPROP 2 LASTPIN (-850 2300) $PN 64
J 2
(-860 2310);
DISPLAY 0.617021 (-860 2310);
PAINT ORANGE (-860 2310);
FORCEPROP 2 LASTPIN (-850 2250) $PN 67
J 2
(-860 2260);
DISPLAY 0.617021 (-860 2260);
PAINT ORANGE (-860 2260);
FORCEPROP 2 LASTPIN (-850 2200) $PN 70
J 2
(-860 2210);
DISPLAY 0.617021 (-860 2210);
PAINT ORANGE (-860 2210);
FORCEPROP 2 LASTPIN (-850 2150) $PN 73
J 2
(-860 2160);
DISPLAY 0.617021 (-860 2160);
PAINT ORANGE (-860 2160);
FORCEPROP 2 LASTPIN (-850 2100) $PN 76
J 2
(-860 2110);
DISPLAY 0.617021 (-860 2110);
PAINT ORANGE (-860 2110);
FORCEPROP 2 LASTPIN (-850 2050) $PN 80
J 2
(-860 2060);
DISPLAY 0.617021 (-860 2060);
PAINT ORANGE (-860 2060);
FORCEPROP 2 LASTPIN (-850 2000) $PN 83
J 2
(-860 2010);
DISPLAY 0.617021 (-860 2010);
PAINT ORANGE (-860 2010);
FORCEPROP 2 LASTPIN (-850 1950) $PN 85
J 2
(-860 1960);
DISPLAY 0.617021 (-860 1960);
PAINT ORANGE (-860 1960);
FORCEPROP 2 LASTPIN (-850 1900) $PN 88
J 2
(-860 1910);
DISPLAY 0.617021 (-860 1910);
PAINT ORANGE (-860 1910);
FORCEPROP 2 LASTPIN (-850 1850) $PN 90
J 2
(-860 1860);
DISPLAY 0.617021 (-860 1860);
PAINT ORANGE (-860 1860);
FORCEPROP 2 LASTPIN (-850 1800) $PN 92
J 2
(-860 1810);
DISPLAY 0.617021 (-860 1810);
PAINT ORANGE (-860 1810);
FORCEPROP 2 LASTPIN (-850 1750) $PN 204
J 2
(-860 1760);
DISPLAY 0.617021 (-860 1760);
PAINT ORANGE (-860 1760);
FORCEPROP 2 LASTPIN (-850 1700) $PN 206
J 2
(-860 1710);
DISPLAY 0.617021 (-860 1710);
PAINT ORANGE (-860 1710);
FORCEPROP 2 LASTPIN (-850 1650) $PN 209
J 2
(-860 1660);
DISPLAY 0.617021 (-860 1660);
PAINT ORANGE (-860 1660);
FORCEPROP 2 LASTPIN (-850 1600) $PN 212
J 2
(-860 1610);
DISPLAY 0.617021 (-860 1610);
PAINT ORANGE (-860 1610);
FORCEPROP 2 LASTPIN (-850 1550) $PN 215
J 2
(-860 1560);
DISPLAY 0.617021 (-860 1560);
PAINT ORANGE (-860 1560);
FORCEPROP 2 LASTPIN (-850 1500) $PN 217
J 2
(-860 1510);
DISPLAY 0.617021 (-860 1510);
PAINT ORANGE (-860 1510);
FORCEPROP 2 LASTPIN (-850 1450) $PN 220
J 2
(-860 1460);
DISPLAY 0.617021 (-860 1460);
PAINT ORANGE (-860 1460);
FORCEPROP 2 LASTPIN (-850 1400) $PN 223
J 2
(-860 1410);
DISPLAY 0.617021 (-860 1410);
PAINT ORANGE (-860 1410);
FORCEPROP 2 LASTPIN (-850 1350) $PN 226
J 2
(-860 1360);
DISPLAY 0.617021 (-860 1360);
PAINT ORANGE (-860 1360);
FORCEPROP 2 LASTPIN (-850 1300) $PN 229
J 2
(-860 1310);
DISPLAY 0.617021 (-860 1310);
PAINT ORANGE (-860 1310);
FORCEPROP 2 LASTPIN (-850 1250) $PN 231
J 2
(-860 1260);
DISPLAY 0.617021 (-860 1260);
PAINT ORANGE (-860 1260);
FORCEPROP 2 LASTPIN (-850 1200) $PN 233
J 2
(-860 1210);
DISPLAY 0.617021 (-860 1210);
PAINT ORANGE (-860 1210);
FORCEPROP 2 LASTPIN (-850 1150) $PN 236
J 2
(-860 1160);
DISPLAY 0.617021 (-860 1160);
PAINT ORANGE (-860 1160);
FORCEPROP 2 LASTPIN (150 2850) $PN 1
J 0
(160 2860);
DISPLAY 0.617021 (160 2860);
PAINT ORANGE (160 2860);
FORCEPROP 2 LASTPIN (150 2800) $PN 145
J 0
(160 2810);
DISPLAY 0.617021 (160 2810);
PAINT ORANGE (160 2810);
FORCEPROP 1 LAST PACK_TYPE PIP
J 0
(-800 3150);
PAINT SKYBLUE (-800 3150);
DISPLAY INVISIBLE (-800 3150);
FORCEPROP 2 LAST BOM_COST MEM
J 0
(-350 2000);
PAINT ORANGE (-350 2000);
DISPLAY INVISIBLE (-350 2000);
FORCEPROP 2 LAST CDS_LIB mstr_sconn
J 0
(-350 2000);
PAINT ORANGE (-350 2000);
DISPLAY INVISIBLE (-350 2000);
FORCEPROP 2 LAST SEC_TYPE PIP
J 0
(-800 3150);
DISPLAY 1.021277 (-800 3150);
PAINT ORANGE (-800 3150);
DISPLAY INVISIBLE (-800 3150);
FORCEPROP 2 LAST SEC 4
J 0
(-800 3150);
DISPLAY 0.680851 (-800 3150);
PAINT MONO (-800 3150);
DISPLAY INVISIBLE (-800 3150);
FORCEPROP 2 LAST CDS_LOCATION J1G3
J 0
(-800 3100);
DISPLAY 0.617021 (-800 3100);
PAINT AQUA (-800 3100);
DISPLAY INVISIBLE (-800 3100);
FORCEPROP 1 LAST PATH I169
J 0
(-350 3050);
PAINT GREEN (-350 3050);
DISPLAY INVISIBLE (-350 3050);
FORCEPROP 2 LAST ROOM DDR4_CH_J
J 0
(-350 2000);
PAINT ORANGE (-350 2000);
DISPLAY INVISIBLE (-350 2000);
FORCEADD PVDDQ_GHJ..1
(-1475 2525);
FORCEPROP 3 LASTPIN (-1475 2475) SIG_NAME PVDDQ_GHJ\g
J 0
(-1465 2485);
DISPLAY 0.659574 (-1465 2485);
PAINT MONO (-1465 2485);
DISPLAY INVISIBLE (-1465 2485);
FORCEPROP 1 LAST VOLTAGE 1.2V
J 0
(-1520 2482);
DISPLAY 0.340426 (-1520 2482);
PAINT SKYBLUE (-1520 2482);
DISPLAY INVISIBLE (-1520 2482);
FORCEPROP 2 LAST BOM_COST MEM
J 0
(-1475 2530);
PAINT ORANGE (-1475 2530);
DISPLAY INVISIBLE (-1475 2530);
FORCEPROP 2 LAST CDS_LIB mstr_symbols
J 0
(-1475 2525);
PAINT ORANGE (-1475 2525);
DISPLAY INVISIBLE (-1475 2525);
FORCEPROP 1 LAST BODY_TYPE PLUMBING
J 0
(-1520 2482);
DISPLAY 0.340426 (-1520 2482);
PAINT GREEN (-1520 2482);
DISPLAY INVISIBLE (-1520 2482);
FORCEPROP 1 LAST PATH I17
J 0
(-1425 2550);
DISPLAY 0.872340 (-1425 2550);
PAINT AQUA (-1425 2550);
DISPLAY INVISIBLE (-1425 2550);
FORCEPROP 2 LAST ROOM DDR4_CH_J
J 0
(-1475 2625);
DISPLAY 0.787234 (-1475 2625);
PAINT ORANGE (-1475 2625);
DISPLAY INVISIBLE (-1475 2625);
FORCEPROP 1 LAST HDL_POWER PVDDQ_GHJ
J 1
(-1475 2575);
DISPLAY 0.872340 (-1475 2575);
PAINT GREEN (-1475 2575);
DISPLAY INVISIBLE (-1475 2575);
FORCEADD GND..1
R 2
(2450 1100);
FORCEPROP 3 LASTPIN (2450 1150) SIG_NAME GND\g
J 0
(2460 1160);
DISPLAY 0.659574 (2460 1160);
PAINT MONO (2460 1160);
DISPLAY INVISIBLE (2460 1160);
FORCEPROP 1 LAST VOLTAGE 0
J 0
(2450 1100);
PAINT SKYBLUE (2450 1100);
DISPLAY INVISIBLE (2450 1100);
FORCEPROP 2 LAST BOM_COST MEM
J 0
(2450 1105);
PAINT ORANGE (2450 1105);
DISPLAY INVISIBLE (2450 1105);
FORCEPROP 2 LAST CDS_LIB mstr_symbols
J 0
(2450 1100);
DISPLAY 0.787234 (2450 1100);
PAINT MONO (2450 1100);
DISPLAY INVISIBLE (2450 1100);
FORCEPROP 1 LAST SIZE 1B
J 2
(2375 1050);
DISPLAY 1.170213 (2375 1050);
PAINT GREEN (2375 1050);
DISPLAY INVISIBLE (2375 1050);
FORCEPROP 1 LAST BODY_TYPE PLUMBING
J 2
(2495 1057);
DISPLAY 0.340426 (2495 1057);
PAINT GREEN (2495 1057);
DISPLAY INVISIBLE (2495 1057);
FORCEPROP 1 LAST PATH I170
J 2
(2375 1100);
DISPLAY 1.404255 (2375 1100);
PAINT GREEN (2375 1100);
DISPLAY INVISIBLE (2375 1100);
FORCEPROP 2 LAST ROOM DDR4_CH_J
J 0
(2450 1105);
PAINT ORANGE (2450 1105);
DISPLAY INVISIBLE (2450 1105);
FORCEPROP 1 LAST HDL_POWER GND
J 2
(2450 1250);
DISPLAY 0.553191 (2450 1250);
PAINT GREEN (2450 1250);
DISPLAY INVISIBLE (2450 1250);
FORCEADD OFFPAGE..1
(-3950 1750);
FORCEPROP 2 LAST $XR5 82 
J 0
(-4651 1750);
DISPLAY 0.638298 (-4651 1750);
PAINT MONO (-4651 1750);
FORCEPROP 2 LAST $XR4 80 
J 0
(-4561 1750);
DISPLAY 0.638298 (-4561 1750);
PAINT MONO (-4561 1750);
FORCEPROP 2 LAST $XR3 79 
J 0
(-4471 1750);
DISPLAY 0.638298 (-4471 1750);
PAINT MONO (-4471 1750);
FORCEPROP 2 LAST $XR2 78 
J 0
(-4381 1750);
DISPLAY 0.638298 (-4381 1750);
PAINT MONO (-4381 1750);
FORCEPROP 2 LAST $XR1 77 
J 0
(-4291 1750);
DISPLAY 0.638298 (-4291 1750);
PAINT MONO (-4291 1750);
FORCEPROP 2 LAST $XR0 99 
J 0
(-4201 1750);
DISPLAY 0.638298 (-4201 1750);
PAINT MONO (-4201 1750);
FORCEPROP 2 LAST CDS_LIB mstr_standard
J 0
(-3950 1750);
DISPLAY 0.787234 (-3950 1750);
PAINT MONO (-3950 1750);
DISPLAY INVISIBLE (-3950 1750);
FORCEPROP 1 LAST OFFPAGE TRUE
J 0
(-3625 1625);
DISPLAY 0.936170 (-3625 1625);
PAINT GREEN (-3625 1625);
DISPLAY INVISIBLE (-3625 1625);
FORCEPROP 1 LAST COMMENT_BODY TRUE
J 0
(-3825 1650);
DISPLAY 0.936170 (-3825 1650);
PAINT GREEN (-3825 1650);
DISPLAY INVISIBLE (-3825 1650);
FORCEPROP 2 LAST PATH I171
J 0
(-4225 1800);
DISPLAY 0.787234 (-4225 1800);
PAINT ORANGE (-4225 1800);
DISPLAY INVISIBLE (-4225 1800);
FORCEADD OFFPAGE..6
(-3950 1800);
FORCEPROP 2 LASTPIN (-3900 1800) SIG_NAME SMB_DDR_GHJ_VPP_SDA
J 0
(-3860 1810);
DISPLAY 0.617021 (-3860 1810);
PAINT ORANGE (-3860 1810);
FORCEPROP 2 LAST $XR5 99 
J 0
(-4679 1800);
DISPLAY 0.638298 (-4679 1800);
PAINT MONO (-4679 1800);
FORCEPROP 2 LAST $XR4 82 
J 0
(-4589 1800);
DISPLAY 0.638298 (-4589 1800);
PAINT MONO (-4589 1800);
FORCEPROP 2 LAST $XR3 80 
J 0
(-4499 1800);
DISPLAY 0.638298 (-4499 1800);
PAINT MONO (-4499 1800);
FORCEPROP 2 LAST $XR2 79 
J 0
(-4409 1800);
DISPLAY 0.638298 (-4409 1800);
PAINT MONO (-4409 1800);
FORCEPROP 2 LAST $XR1 78 
J 0
(-4319 1800);
DISPLAY 0.638298 (-4319 1800);
PAINT MONO (-4319 1800);
FORCEPROP 2 LAST $XR0 77 
J 0
(-4229 1800);
DISPLAY 0.638298 (-4229 1800);
PAINT MONO (-4229 1800);
FORCEPROP 2 LAST CDS_LIB mstr_standard
J 0
(-3950 1800);
DISPLAY 0.787234 (-3950 1800);
PAINT MONO (-3950 1800);
DISPLAY INVISIBLE (-3950 1800);
FORCEPROP 1 LAST OFFPAGE TRUE
J 0
(-3625 1675);
DISPLAY 0.936170 (-3625 1675);
PAINT GREEN (-3625 1675);
DISPLAY INVISIBLE (-3625 1675);
FORCEPROP 1 LAST COMMENT_BODY TRUE
J 0
(-3850 1725);
DISPLAY 0.936170 (-3850 1725);
PAINT GREEN (-3850 1725);
DISPLAY INVISIBLE (-3850 1725);
FORCEPROP 2 LAST PATH I172
J 0
(-4275 1850);
DISPLAY 0.787234 (-4275 1850);
PAINT ORANGE (-4275 1850);
DISPLAY INVISIBLE (-4275 1850);
FORCEADD OFFPAGE..1
(-4700 1650);
FORCEPROP 2 LAST $XR1 82 
J 0
(-5042 1650);
DISPLAY 0.638298 (-5042 1650);
PAINT MONO (-5042 1650);
FORCEPROP 2 LAST $XR0 100 
J 0
(-4952 1650);
DISPLAY 0.638298 (-4952 1650);
PAINT MONO (-4952 1650);
FORCEPROP 2 LAST CDS_LIB mstr_standard
J 0
(-4700 1650);
DISPLAY 0.787234 (-4700 1650);
PAINT MONO (-4700 1650);
DISPLAY INVISIBLE (-4700 1650);
FORCEPROP 1 LAST OFFPAGE TRUE
J 0
(-4375 1525);
DISPLAY 0.936170 (-4375 1525);
PAINT GREEN (-4375 1525);
DISPLAY INVISIBLE (-4375 1525);
FORCEPROP 1 LAST COMMENT_BODY TRUE
J 0
(-4575 1550);
DISPLAY 0.936170 (-4575 1550);
PAINT GREEN (-4575 1550);
DISPLAY INVISIBLE (-4575 1550);
FORCEPROP 2 LAST PATH I173
J 0
(-4950 1700);
DISPLAY 0.787234 (-4950 1700);
PAINT ORANGE (-4950 1700);
DISPLAY INVISIBLE (-4950 1700);
FORCEADD GND..1
R 2
(-5200 1750);
FORCEPROP 3 LASTPIN (-5200 1800) SIG_NAME GND\g
J 0
(-5190 1810);
DISPLAY 0.659574 (-5190 1810);
PAINT MONO (-5190 1810);
DISPLAY INVISIBLE (-5190 1810);
FORCEPROP 1 LAST VOLTAGE 0
J 0
(-5200 1750);
PAINT SKYBLUE (-5200 1750);
DISPLAY INVISIBLE (-5200 1750);
FORCEPROP 2 LAST BOM_COST MEM
J 0
(-5200 1755);
PAINT ORANGE (-5200 1755);
DISPLAY INVISIBLE (-5200 1755);
FORCEPROP 2 LAST CDS_LIB mstr_symbols
J 0
(-5200 1750);
DISPLAY 0.787234 (-5200 1750);
PAINT MONO (-5200 1750);
DISPLAY INVISIBLE (-5200 1750);
FORCEPROP 1 LAST SIZE 1B
J 2
(-5275 1700);
DISPLAY 1.170213 (-5275 1700);
PAINT GREEN (-5275 1700);
DISPLAY INVISIBLE (-5275 1700);
FORCEPROP 1 LAST BODY_TYPE PLUMBING
J 2
(-5155 1707);
DISPLAY 0.340426 (-5155 1707);
PAINT GREEN (-5155 1707);
DISPLAY INVISIBLE (-5155 1707);
FORCEPROP 1 LAST PATH I175
J 2
(-5275 1750);
DISPLAY 1.404255 (-5275 1750);
PAINT GREEN (-5275 1750);
DISPLAY INVISIBLE (-5275 1750);
FORCEPROP 2 LAST ROOM DDR4_CH_J
J 0
(-5200 1755);
PAINT ORANGE (-5200 1755);
DISPLAY INVISIBLE (-5200 1755);
FORCEPROP 1 LAST HDL_POWER GND
J 2
(-5200 1900);
DISPLAY 0.553191 (-5200 1900);
PAINT GREEN (-5200 1900);
DISPLAY INVISIBLE (-5200 1900);
FORCEADD OFFPAGE..5
(-4325 2450);
FORCEPROP 2 LAST $XR23 94 
J 0
(-5029 2486);
DISPLAY 0.638298 (-5029 2486);
PAINT MONO (-5029 2486);
FORCEPROP 2 LAST $XR22 88 
J 0
(-4939 2486);
DISPLAY 0.638298 (-4939 2486);
PAINT MONO (-4939 2486);
FORCEPROP 2 LAST $XR21 87 
J 0
(-4849 2486);
DISPLAY 0.638298 (-4849 2486);
PAINT MONO (-4849 2486);
FORCEPROP 2 LAST $XR20 86 
J 0
(-4759 2486);
DISPLAY 0.638298 (-4759 2486);
PAINT MONO (-4759 2486);
FORCEPROP 2 LAST $XR19 85 
J 0
(-4669 2486);
DISPLAY 0.638298 (-4669 2486);
PAINT MONO (-4669 2486);
FORCEPROP 2 LAST $XR18 84 
J 0
(-4579 2486);
DISPLAY 0.638298 (-4579 2486);
PAINT MONO (-4579 2486);
FORCEPROP 2 LAST $XR17 83 
J 0
(-5299 2414);
DISPLAY 0.638298 (-5299 2414);
PAINT MONO (-5299 2414);
FORCEPROP 2 LAST $XR16 82 
J 0
(-5209 2414);
DISPLAY 0.638298 (-5209 2414);
PAINT MONO (-5209 2414);
FORCEPROP 2 LAST $XR15 80 
J 0
(-5119 2414);
DISPLAY 0.638298 (-5119 2414);
PAINT MONO (-5119 2414);
FORCEPROP 2 LAST $XR14 79 
J 0
(-5029 2414);
DISPLAY 0.638298 (-5029 2414);
PAINT MONO (-5029 2414);
FORCEPROP 2 LAST $XR13 78 
J 0
(-4939 2414);
DISPLAY 0.638298 (-4939 2414);
PAINT MONO (-4939 2414);
FORCEPROP 2 LAST $XR12 77 
J 0
(-4849 2414);
DISPLAY 0.638298 (-4849 2414);
PAINT MONO (-4849 2414);
FORCEPROP 2 LAST $XR11 54 
J 0
(-4759 2414);
DISPLAY 0.638298 (-4759 2414);
PAINT MONO (-4759 2414);
FORCEPROP 2 LAST $XR10 53 
J 0
(-4669 2414);
DISPLAY 0.638298 (-4669 2414);
PAINT MONO (-4669 2414);
FORCEPROP 2 LAST $XR9 52 
J 0
(-4579 2414);
DISPLAY 0.638298 (-4579 2414);
PAINT MONO (-4579 2414);
FORCEPROP 2 LAST $XR8 51 
J 0
(-5299 2450);
DISPLAY 0.638298 (-5299 2450);
PAINT MONO (-5299 2450);
FORCEPROP 2 LAST $XR7 50 
J 0
(-5209 2450);
DISPLAY 0.638298 (-5209 2450);
PAINT MONO (-5209 2450);
FORCEPROP 2 LAST $XR6 49 
J 0
(-5119 2450);
DISPLAY 0.638298 (-5119 2450);
PAINT MONO (-5119 2450);
FORCEPROP 2 LAST $XR5 48 
J 0
(-5029 2450);
DISPLAY 0.638298 (-5029 2450);
PAINT MONO (-5029 2450);
FORCEPROP 2 LAST $XR4 47 
J 0
(-4939 2450);
DISPLAY 0.638298 (-4939 2450);
PAINT MONO (-4939 2450);
FORCEPROP 2 LAST $XR3 46 
J 0
(-4849 2450);
DISPLAY 0.638298 (-4849 2450);
PAINT MONO (-4849 2450);
FORCEPROP 2 LAST $XR2 45 
J 0
(-4759 2450);
DISPLAY 0.638298 (-4759 2450);
PAINT MONO (-4759 2450);
FORCEPROP 2 LAST $XR1 44 
J 0
(-4669 2450);
DISPLAY 0.638298 (-4669 2450);
PAINT MONO (-4669 2450);
FORCEPROP 2 LAST $XR0 43 
J 0
(-4579 2450);
DISPLAY 0.638298 (-4579 2450);
PAINT MONO (-4579 2450);
FORCEPROP 2 LAST CDS_LIB mstr_standard
J 0
(-4325 2450);
DISPLAY 0.787234 (-4325 2450);
PAINT MONO (-4325 2450);
DISPLAY INVISIBLE (-4325 2450);
FORCEPROP 1 LAST OFFPAGE TRUE
J 0
(-4000 2325);
DISPLAY 1.404255 (-4000 2325);
PAINT GREEN (-4000 2325);
DISPLAY INVISIBLE (-4000 2325);
FORCEPROP 1 LAST COMMENT_BODY TRUE
J 0
(-4225 2375);
DISPLAY 1.404255 (-4225 2375);
PAINT GREEN (-4225 2375);
DISPLAY INVISIBLE (-4225 2375);
FORCEPROP 2 LAST PATH I176
J 0
(-4275 2525);
DISPLAY 0.787234 (-4275 2525);
PAINT ORANGE (-4275 2525);
DISPLAY INVISIBLE (-4275 2525);
FORCEADD GND..1
(-4550 1200);
FORCEPROP 3 LASTPIN (-4550 1250) SIG_NAME GND\g
J 0
(-4540 1260);
DISPLAY 0.659574 (-4540 1260);
PAINT MONO (-4540 1260);
DISPLAY INVISIBLE (-4540 1260);
FORCEPROP 1 LAST VOLTAGE 0
J 0
(-4550 1200);
PAINT SKYBLUE (-4550 1200);
DISPLAY INVISIBLE (-4550 1200);
FORCEPROP 2 LAST CDS_LIB mstr_symbols
J 0
(-4550 1200);
PAINT ORANGE (-4550 1200);
DISPLAY INVISIBLE (-4550 1200);
FORCEPROP 1 LAST SIZE 1B
J 0
(-4475 1150);
DISPLAY 1.787234 (-4475 1150);
PAINT GREEN (-4475 1150);
DISPLAY INVISIBLE (-4475 1150);
FORCEPROP 2 LAST BOM_COST MEM
J 0
(-4550 1205);
PAINT ORANGE (-4550 1205);
DISPLAY INVISIBLE (-4550 1205);
FORCEPROP 1 LAST BODY_TYPE PLUMBING
J 0
(-4595 1157);
DISPLAY 0.340426 (-4595 1157);
PAINT GREEN (-4595 1157);
DISPLAY INVISIBLE (-4595 1157);
FORCEPROP 1 LAST PATH I177
J 0
(-4475 1200);
DISPLAY 1.404255 (-4475 1200);
PAINT GREEN (-4475 1200);
DISPLAY INVISIBLE (-4475 1200);
FORCEPROP 2 LAST ROOM DDR4_CH_J
J 0
(-4550 1205);
PAINT ORANGE (-4550 1205);
DISPLAY INVISIBLE (-4550 1205);
FORCEPROP 1 LAST HDL_POWER GND
J 0
(-4550 1350);
DISPLAY 1.404255 (-4550 1350);
PAINT GREEN (-4550 1350);
DISPLAY INVISIBLE (-4550 1350);
FORCEADD CAP_A..1
R 2
(-4550 1450);
FORCEPROP 1 LAST LOCATION C9U10
J 2
(-4600 1550);
DISPLAY 0.617021 (-4600 1550);
PAINT AQUA (-4600 1550);
FORCEPROP 1 LAST PART_NUMBER A36096-045
J 2
(-4600 1300);
DISPLAY 0.617021 (-4600 1300);
PAINT BLUE (-4600 1300);
FORCEPROP 1 LAST VALUE 0.01UF
J 2
(-4600 1500);
DISPLAY 0.617021 (-4600 1500);
PAINT SKYBLUE (-4600 1500);
FORCEPROP 1 LAST TOLERANCE 10%
J 2
(-4600 1400);
DISPLAY 0.617021 (-4600 1400);
PAINT SKYBLUE (-4600 1400);
FORCEPROP 1 LAST PACK_TYPE 0402V
J 2
(-4600 1250);
DISPLAY 0.617021 (-4600 1250);
PAINT SKYBLUE (-4600 1250);
FORCEPROP 1 LAST VOLTAGE 25V
J 2
(-4600 1450);
DISPLAY 0.617021 (-4600 1450);
PAINT SKYBLUE (-4600 1450);
FORCEPROP 1 LAST MATERIAL X7R
J 2
(-4600 1350);
DISPLAY 0.617021 (-4600 1350);
PAINT SKYBLUE (-4600 1350);
FORCEPROP 2 LAST CDS_LOCATION C9U10
J 2
(-4600 1550);
DISPLAY 0.617021 (-4600 1550);
PAINT AQUA (-4600 1550);
DISPLAY INVISIBLE (-4600 1550);
FORCEPROP 2 LAST BOM_COST MEM
J 0
(-4550 1450);
PAINT ORANGE (-4550 1450);
DISPLAY INVISIBLE (-4550 1450);
FORCEPROP 2 LAST CDS_LIB dev_discrete
J 0
(-4550 1450);
PAINT ORANGE (-4550 1450);
DISPLAY INVISIBLE (-4550 1450);
FORCEPROP 2 LAST CDS_SEC 1
J 2
(-4600 1650);
PAINT MONO (-4600 1650);
DISPLAY INVISIBLE (-4600 1650);
FORCEPROP 2 LAST $SEC 1
J 0
(-4600 1650);
PAINT MONO (-4600 1650);
DISPLAY INVISIBLE (-4600 1650);
FORCEPROP 1 LAST PATH I178
J 2
(-4600 1600);
DISPLAY 0.978723 (-4600 1600);
PAINT WHITE (-4600 1600);
DISPLAY INVISIBLE (-4600 1600);
FORCEPROP 2 LAST ROOM DDR4_CH_J
J 0
(-4550 1450);
PAINT ORANGE (-4550 1450);
DISPLAY INVISIBLE (-4550 1450);
FORCEPROP 1 LASTPIN (-4550 1550) $PN 1
J 2
(-4560 1530);
DISPLAY 0.787234 (-4560 1530);
PAINT ORANGE (-4560 1530);
DISPLAY INVISIBLE (-4560 1530);
FORCEPROP 1 LASTPIN (-4550 1350) $PN 2
J 2
(-4560 1330);
DISPLAY 0.787234 (-4560 1330);
PAINT ORANGE (-4560 1330);
DISPLAY INVISIBLE (-4560 1330);
FORCEADD PVPP_GHJ..1
(-1050 3000);
FORCEPROP 3 LASTPIN (-1050 2950) SIG_NAME PVPP_GHJ\g
J 0
(-1040 2960);
DISPLAY 0.659574 (-1040 2960);
PAINT MONO (-1040 2960);
DISPLAY INVISIBLE (-1040 2960);
FORCEPROP 1 LAST VOLTAGE 2.5V
J 0
(-1095 2957);
DISPLAY 0.340426 (-1095 2957);
PAINT SKYBLUE (-1095 2957);
DISPLAY INVISIBLE (-1095 2957);
FORCEPROP 0 LAST BOM_COST MEM
J 0
(-1050 3100);
PAINT ORANGE (-1050 3100);
DISPLAY INVISIBLE (-1050 3100);
FORCEPROP 2 LAST CDS_LIB mstr_symbols
J 0
(-1050 3000);
PAINT ORANGE (-1050 3000);
DISPLAY INVISIBLE (-1050 3000);
FORCEPROP 1 LAST BODY_TYPE PLUMBING
J 0
(-1095 2957);
DISPLAY 0.340426 (-1095 2957);
PAINT GREEN (-1095 2957);
DISPLAY INVISIBLE (-1095 2957);
FORCEPROP 1 LAST PATH I179
J 0
(-1000 3025);
DISPLAY 0.872340 (-1000 3025);
PAINT AQUA (-1000 3025);
DISPLAY INVISIBLE (-1000 3025);
FORCEPROP 2 LAST ROOM DDR4_CH_J
J 0
(-1050 3100);
PAINT ORANGE (-1050 3100);
DISPLAY INVISIBLE (-1050 3100);
FORCEPROP 1 LAST HDL_POWER PVPP_GHJ
J 1
(-1050 3050);
DISPLAY 0.872340 (-1050 3050);
PAINT GREEN (-1050 3050);
DISPLAY INVISIBLE (-1050 3050);
FORCEADD PVTT_GHJ..1
(-1200 2700);
FORCEPROP 3 LASTPIN (-1200 2650) SIG_NAME PVTT_GHJ\g
J 0
(-1190 2660);
DISPLAY 0.659574 (-1190 2660);
PAINT MONO (-1190 2660);
DISPLAY INVISIBLE (-1190 2660);
FORCEPROP 1 LAST VOLTAGE 0.6V
J 0
(-1245 2657);
DISPLAY 0.340426 (-1245 2657);
PAINT SKYBLUE (-1245 2657);
DISPLAY INVISIBLE (-1245 2657);
FORCEPROP 2 LAST BOM_COST MEM
J 0
(-1200 2705);
PAINT ORANGE (-1200 2705);
DISPLAY INVISIBLE (-1200 2705);
FORCEPROP 2 LAST CDS_LIB mstr_symbols
J 0
(-1200 2700);
PAINT ORANGE (-1200 2700);
DISPLAY INVISIBLE (-1200 2700);
FORCEPROP 1 LAST BODY_TYPE PLUMBING
J 0
(-1245 2657);
DISPLAY 0.340426 (-1245 2657);
PAINT GREEN (-1245 2657);
DISPLAY INVISIBLE (-1245 2657);
FORCEPROP 1 LAST PATH I18
J 0
(-1150 2725);
DISPLAY 0.872340 (-1150 2725);
PAINT AQUA (-1150 2725);
DISPLAY INVISIBLE (-1150 2725);
FORCEPROP 2 LAST ROOM DDR4_CH_J
J 0
(-1200 2800);
DISPLAY 0.787234 (-1200 2800);
PAINT ORANGE (-1200 2800);
DISPLAY INVISIBLE (-1200 2800);
FORCEPROP 1 LAST HDL_POWER PVTT_GHJ
J 1
(-1200 2750);
DISPLAY 0.872340 (-1200 2750);
PAINT GREEN (-1200 2750);
DISPLAY INVISIBLE (-1200 2750);
FORCEADD PVPP_GHJ..1
(-5200 2150);
FORCEPROP 3 LASTPIN (-5200 2100) SIG_NAME PVPP_GHJ\g
J 0
(-5190 2110);
DISPLAY 0.659574 (-5190 2110);
PAINT MONO (-5190 2110);
DISPLAY INVISIBLE (-5190 2110);
FORCEPROP 1 LAST VOLTAGE 2.5V
J 0
(-5245 2107);
DISPLAY 0.340426 (-5245 2107);
PAINT SKYBLUE (-5245 2107);
DISPLAY INVISIBLE (-5245 2107);
FORCEPROP 0 LAST BOM_COST MEM
J 0
(-5200 2250);
PAINT ORANGE (-5200 2250);
DISPLAY INVISIBLE (-5200 2250);
FORCEPROP 2 LAST CDS_LIB mstr_symbols
J 0
(-5200 2150);
PAINT ORANGE (-5200 2150);
DISPLAY INVISIBLE (-5200 2150);
FORCEPROP 1 LAST BODY_TYPE PLUMBING
J 0
(-5245 2107);
DISPLAY 0.340426 (-5245 2107);
PAINT GREEN (-5245 2107);
DISPLAY INVISIBLE (-5245 2107);
FORCEPROP 1 LAST PATH I180
J 0
(-5150 2175);
DISPLAY 0.872340 (-5150 2175);
PAINT AQUA (-5150 2175);
DISPLAY INVISIBLE (-5150 2175);
FORCEPROP 2 LAST ROOM DDR4_CH_J
J 0
(-5200 2250);
PAINT ORANGE (-5200 2250);
DISPLAY INVISIBLE (-5200 2250);
FORCEPROP 1 LAST HDL_POWER PVPP_GHJ
J 1
(-5200 2200);
DISPLAY 0.872340 (-5200 2200);
PAINT GREEN (-5200 2200);
DISPLAY INVISIBLE (-5200 2200);
FORCEADD OFFPAGE..1
(-3950 1350);
FORCEPROP 2 LAST $XR5 82 
J 0
(-4171 1314);
DISPLAY 0.638298 (-4171 1314);
PAINT MONO (-4171 1314);
FORCEPROP 2 LAST $XR4 80 
J 0
(-4531 1350);
DISPLAY 0.638298 (-4531 1350);
PAINT MONO (-4531 1350);
FORCEPROP 2 LAST $XR3 79 
J 0
(-4441 1350);
DISPLAY 0.638298 (-4441 1350);
PAINT MONO (-4441 1350);
FORCEPROP 2 LAST $XR2 78 
J 0
(-4351 1350);
DISPLAY 0.638298 (-4351 1350);
PAINT MONO (-4351 1350);
FORCEPROP 2 LAST $XR1 77 
J 0
(-4261 1350);
DISPLAY 0.638298 (-4261 1350);
PAINT MONO (-4261 1350);
FORCEPROP 2 LAST $XR0 89 
J 0
(-4171 1350);
DISPLAY 0.638298 (-4171 1350);
PAINT MONO (-4171 1350);
FORCEPROP 2 LAST CDS_LIB mstr_standard
J 0
(-3950 1350);
PAINT ORANGE (-3950 1350);
DISPLAY INVISIBLE (-3950 1350);
FORCEPROP 1 LAST OFFPAGE TRUE
J 0
(-3625 1225);
DISPLAY 0.936170 (-3625 1225);
PAINT GREEN (-3625 1225);
DISPLAY INVISIBLE (-3625 1225);
FORCEPROP 1 LAST COMMENT_BODY TRUE
J 0
(-3825 1250);
DISPLAY 0.936170 (-3825 1250);
PAINT GREEN (-3825 1250);
DISPLAY INVISIBLE (-3825 1250);
FORCEPROP 2 LAST PATH I181
J 0
(-3900 1425);
PAINT ORANGE (-3900 1425);
DISPLAY INVISIBLE (-3900 1425);
FORCEADD SCONN288_H44441004..3
(1750 2400);
FORCEPROP 1 LAST LOCATION J1G3
J 0
(1300 3800);
DISPLAY 0.617021 (1300 3800);
PAINT AQUA (1300 3800);
FORCEPROP 1 LAST PART_NUMBER H44441-004
J 0
(1300 1050);
DISPLAY 0.617021 (1300 1050);
PAINT BLUE (1300 1050);
FORCEPROP 1 LAST MATERIAL SCONN
J 0
(1300 3750);
DISPLAY 0.617021 (1300 3750);
PAINT SKYBLUE (1300 3750);
FORCEPROP 2 LASTPIN (1250 3550) $PN 2
J 2
(1240 3560);
DISPLAY 0.617021 (1240 3560);
PAINT ORANGE (1240 3560);
FORCEPROP 2 LASTPIN (1250 3500) $PN 4
J 2
(1240 3510);
DISPLAY 0.617021 (1240 3510);
PAINT ORANGE (1240 3510);
FORCEPROP 2 LASTPIN (1250 3450) $PN 6
J 2
(1240 3460);
DISPLAY 0.617021 (1240 3460);
PAINT ORANGE (1240 3460);
FORCEPROP 2 LASTPIN (1250 3400) $PN 9
J 2
(1240 3410);
DISPLAY 0.617021 (1240 3410);
PAINT ORANGE (1240 3410);
FORCEPROP 2 LASTPIN (1250 3350) $PN 11
J 2
(1240 3360);
DISPLAY 0.617021 (1240 3360);
PAINT ORANGE (1240 3360);
FORCEPROP 2 LASTPIN (1250 3300) $PN 13
J 2
(1240 3310);
DISPLAY 0.617021 (1240 3310);
PAINT ORANGE (1240 3310);
FORCEPROP 2 LASTPIN (1250 3250) $PN 15
J 2
(1240 3260);
DISPLAY 0.617021 (1240 3260);
PAINT ORANGE (1240 3260);
FORCEPROP 2 LASTPIN (1250 3200) $PN 17
J 2
(1240 3210);
DISPLAY 0.617021 (1240 3210);
PAINT ORANGE (1240 3210);
FORCEPROP 2 LASTPIN (1250 3150) $PN 20
J 2
(1240 3160);
DISPLAY 0.617021 (1240 3160);
PAINT ORANGE (1240 3160);
FORCEPROP 2 LASTPIN (1250 3050) $PN 24
J 2
(1240 3060);
DISPLAY 0.617021 (1240 3060);
PAINT ORANGE (1240 3060);
FORCEPROP 2 LASTPIN (1250 3000) $PN 26
J 2
(1240 3010);
DISPLAY 0.617021 (1240 3010);
PAINT ORANGE (1240 3010);
FORCEPROP 2 LASTPIN (1250 2950) $PN 28
J 2
(1240 2960);
DISPLAY 0.617021 (1240 2960);
PAINT ORANGE (1240 2960);
FORCEPROP 2 LASTPIN (1250 2900) $PN 31
J 2
(1240 2910);
DISPLAY 0.617021 (1240 2910);
PAINT ORANGE (1240 2910);
FORCEPROP 2 LASTPIN (1250 2850) $PN 33
J 2
(1240 2860);
DISPLAY 0.617021 (1240 2860);
PAINT ORANGE (1240 2860);
FORCEPROP 2 LASTPIN (1250 2800) $PN 35
J 2
(1240 2810);
DISPLAY 0.617021 (1240 2810);
PAINT ORANGE (1240 2810);
FORCEPROP 2 LASTPIN (1250 2750) $PN 37
J 2
(1240 2760);
DISPLAY 0.617021 (1240 2760);
PAINT ORANGE (1240 2760);
FORCEPROP 2 LASTPIN (1250 2700) $PN 39
J 2
(1240 2710);
DISPLAY 0.617021 (1240 2710);
PAINT ORANGE (1240 2710);
FORCEPROP 2 LASTPIN (1250 2650) $PN 42
J 2
(1240 2660);
DISPLAY 0.617021 (1240 2660);
PAINT ORANGE (1240 2660);
FORCEPROP 2 LASTPIN (1250 2600) $PN 44
J 2
(1240 2610);
DISPLAY 0.617021 (1240 2610);
PAINT ORANGE (1240 2610);
FORCEPROP 2 LASTPIN (1250 2550) $PN 46
J 2
(1240 2560);
DISPLAY 0.617021 (1240 2560);
PAINT ORANGE (1240 2560);
FORCEPROP 2 LASTPIN (1250 2500) $PN 48
J 2
(1240 2510);
DISPLAY 0.617021 (1240 2510);
PAINT ORANGE (1240 2510);
FORCEPROP 2 LASTPIN (1250 2450) $PN 50
J 2
(1240 2460);
DISPLAY 0.617021 (1240 2460);
PAINT ORANGE (1240 2460);
FORCEPROP 2 LASTPIN (1250 2400) $PN 53
J 2
(1240 2410);
DISPLAY 0.617021 (1240 2410);
PAINT ORANGE (1240 2410);
FORCEPROP 2 LASTPIN (1250 2350) $PN 55
J 2
(1240 2360);
DISPLAY 0.617021 (1240 2360);
PAINT ORANGE (1240 2360);
FORCEPROP 2 LASTPIN (1250 2300) $PN 57
J 2
(1240 2310);
DISPLAY 0.617021 (1240 2310);
PAINT ORANGE (1240 2310);
FORCEPROP 2 LASTPIN (1250 2250) $PN 94
J 2
(1240 2260);
DISPLAY 0.617021 (1240 2260);
PAINT ORANGE (1240 2260);
FORCEPROP 2 LASTPIN (1250 2200) $PN 96
J 2
(1240 2210);
DISPLAY 0.617021 (1240 2210);
PAINT ORANGE (1240 2210);
FORCEPROP 2 LASTPIN (1250 2150) $PN 98
J 2
(1240 2160);
DISPLAY 0.617021 (1240 2160);
PAINT ORANGE (1240 2160);
FORCEPROP 2 LASTPIN (1250 2100) $PN 101
J 2
(1240 2110);
DISPLAY 0.617021 (1240 2110);
PAINT ORANGE (1240 2110);
FORCEPROP 2 LASTPIN (1250 2050) $PN 103
J 2
(1240 2060);
DISPLAY 0.617021 (1240 2060);
PAINT ORANGE (1240 2060);
FORCEPROP 2 LASTPIN (1250 2000) $PN 105
J 2
(1240 2010);
DISPLAY 0.617021 (1240 2010);
PAINT ORANGE (1240 2010);
FORCEPROP 2 LASTPIN (1250 1950) $PN 107
J 2
(1240 1960);
DISPLAY 0.617021 (1240 1960);
PAINT ORANGE (1240 1960);
FORCEPROP 2 LASTPIN (1250 1900) $PN 109
J 2
(1240 1910);
DISPLAY 0.617021 (1240 1910);
PAINT ORANGE (1240 1910);
FORCEPROP 2 LASTPIN (1250 1850) $PN 112
J 2
(1240 1860);
DISPLAY 0.617021 (1240 1860);
PAINT ORANGE (1240 1860);
FORCEPROP 2 LASTPIN (1250 1800) $PN 114
J 2
(1240 1810);
DISPLAY 0.617021 (1240 1810);
PAINT ORANGE (1240 1810);
FORCEPROP 2 LASTPIN (1250 1750) $PN 116
J 2
(1240 1760);
DISPLAY 0.617021 (1240 1760);
PAINT ORANGE (1240 1760);
FORCEPROP 2 LASTPIN (1250 1700) $PN 118
J 2
(1240 1710);
DISPLAY 0.617021 (1240 1710);
PAINT ORANGE (1240 1710);
FORCEPROP 2 LASTPIN (1250 1650) $PN 120
J 2
(1240 1660);
DISPLAY 0.617021 (1240 1660);
PAINT ORANGE (1240 1660);
FORCEPROP 2 LASTPIN (1250 1600) $PN 123
J 2
(1240 1610);
DISPLAY 0.617021 (1240 1610);
PAINT ORANGE (1240 1610);
FORCEPROP 2 LASTPIN (1250 1550) $PN 125
J 2
(1240 1560);
DISPLAY 0.617021 (1240 1560);
PAINT ORANGE (1240 1560);
FORCEPROP 2 LASTPIN (1250 1500) $PN 127
J 2
(1240 1510);
DISPLAY 0.617021 (1240 1510);
PAINT ORANGE (1240 1510);
FORCEPROP 2 LASTPIN (1250 1450) $PN 129
J 2
(1240 1460);
DISPLAY 0.617021 (1240 1460);
PAINT ORANGE (1240 1460);
FORCEPROP 2 LASTPIN (1250 1400) $PN 131
J 2
(1240 1410);
DISPLAY 0.617021 (1240 1410);
PAINT ORANGE (1240 1410);
FORCEPROP 2 LASTPIN (1250 1350) $PN 134
J 2
(1240 1360);
DISPLAY 0.617021 (1240 1360);
PAINT ORANGE (1240 1360);
FORCEPROP 2 LASTPIN (1250 1300) $PN 136
J 2
(1240 1310);
DISPLAY 0.617021 (1240 1310);
PAINT ORANGE (1240 1310);
FORCEPROP 2 LASTPIN (1250 1250) $PN 138
J 2
(1240 1260);
DISPLAY 0.617021 (1240 1260);
PAINT ORANGE (1240 1260);
FORCEPROP 2 LASTPIN (2250 3550) $PN 147
J 0
(2260 3560);
DISPLAY 0.617021 (2260 3560);
PAINT ORANGE (2260 3560);
FORCEPROP 2 LASTPIN (2250 3500) $PN 149
J 0
(2260 3510);
DISPLAY 0.617021 (2260 3510);
PAINT ORANGE (2260 3510);
FORCEPROP 2 LASTPIN (2250 3450) $PN 151
J 0
(2260 3460);
DISPLAY 0.617021 (2260 3460);
PAINT ORANGE (2260 3460);
FORCEPROP 2 LASTPIN (2250 3400) $PN 154
J 0
(2260 3410);
DISPLAY 0.617021 (2260 3410);
PAINT ORANGE (2260 3410);
FORCEPROP 2 LASTPIN (2250 3350) $PN 156
J 0
(2260 3360);
DISPLAY 0.617021 (2260 3360);
PAINT ORANGE (2260 3360);
FORCEPROP 2 LASTPIN (2250 3300) $PN 158
J 0
(2260 3310);
DISPLAY 0.617021 (2260 3310);
PAINT ORANGE (2260 3310);
FORCEPROP 2 LASTPIN (2250 3250) $PN 160
J 0
(2260 3260);
DISPLAY 0.617021 (2260 3260);
PAINT ORANGE (2260 3260);
FORCEPROP 2 LASTPIN (2250 3150) $PN 165
J 0
(2260 3160);
DISPLAY 0.617021 (2260 3160);
PAINT ORANGE (2260 3160);
FORCEPROP 2 LASTPIN (2250 3100) $PN 167
J 0
(2260 3110);
DISPLAY 0.617021 (2260 3110);
PAINT ORANGE (2260 3110);
FORCEPROP 2 LASTPIN (2250 3050) $PN 169
J 0
(2260 3060);
DISPLAY 0.617021 (2260 3060);
PAINT ORANGE (2260 3060);
FORCEPROP 2 LASTPIN (2250 3000) $PN 171
J 0
(2260 3010);
DISPLAY 0.617021 (2260 3010);
PAINT ORANGE (2260 3010);
FORCEPROP 2 LASTPIN (2250 2950) $PN 173
J 0
(2260 2960);
DISPLAY 0.617021 (2260 2960);
PAINT ORANGE (2260 2960);
FORCEPROP 2 LASTPIN (2250 2850) $PN 178
J 0
(2260 2860);
DISPLAY 0.617021 (2260 2860);
PAINT ORANGE (2260 2860);
FORCEPROP 2 LASTPIN (2250 2800) $PN 180
J 0
(2260 2810);
DISPLAY 0.617021 (2260 2810);
PAINT ORANGE (2260 2810);
FORCEPROP 2 LASTPIN (2250 2750) $PN 182
J 0
(2260 2760);
DISPLAY 0.617021 (2260 2760);
PAINT ORANGE (2260 2760);
FORCEPROP 2 LASTPIN (2250 2700) $PN 184
J 0
(2260 2710);
DISPLAY 0.617021 (2260 2710);
PAINT ORANGE (2260 2710);
FORCEPROP 2 LASTPIN (2250 2650) $PN 187
J 0
(2260 2660);
DISPLAY 0.617021 (2260 2660);
PAINT ORANGE (2260 2660);
FORCEPROP 2 LASTPIN (2250 2600) $PN 189
J 0
(2260 2610);
DISPLAY 0.617021 (2260 2610);
PAINT ORANGE (2260 2610);
FORCEPROP 2 LASTPIN (2250 2550) $PN 191
J 0
(2260 2560);
DISPLAY 0.617021 (2260 2560);
PAINT ORANGE (2260 2560);
FORCEPROP 2 LASTPIN (2250 2500) $PN 193
J 0
(2260 2510);
DISPLAY 0.617021 (2260 2510);
PAINT ORANGE (2260 2510);
FORCEPROP 2 LASTPIN (2250 2450) $PN 195
J 0
(2260 2460);
DISPLAY 0.617021 (2260 2460);
PAINT ORANGE (2260 2460);
FORCEPROP 2 LASTPIN (2250 2400) $PN 198
J 0
(2260 2410);
DISPLAY 0.617021 (2260 2410);
PAINT ORANGE (2260 2410);
FORCEPROP 2 LASTPIN (2250 2350) $PN 200
J 0
(2260 2360);
DISPLAY 0.617021 (2260 2360);
PAINT ORANGE (2260 2360);
FORCEPROP 2 LASTPIN (2250 2300) $PN 202
J 0
(2260 2310);
DISPLAY 0.617021 (2260 2310);
PAINT ORANGE (2260 2310);
FORCEPROP 2 LASTPIN (2250 2250) $PN 239
J 0
(2260 2260);
DISPLAY 0.617021 (2260 2260);
PAINT ORANGE (2260 2260);
FORCEPROP 2 LASTPIN (2250 2200) $PN 241
J 0
(2260 2210);
DISPLAY 0.617021 (2260 2210);
PAINT ORANGE (2260 2210);
FORCEPROP 2 LASTPIN (2250 2150) $PN 243
J 0
(2260 2160);
DISPLAY 0.617021 (2260 2160);
PAINT ORANGE (2260 2160);
FORCEPROP 2 LASTPIN (2250 2100) $PN 246
J 0
(2260 2110);
DISPLAY 0.617021 (2260 2110);
PAINT ORANGE (2260 2110);
FORCEPROP 2 LASTPIN (2250 2050) $PN 248
J 0
(2260 2060);
DISPLAY 0.617021 (2260 2060);
PAINT ORANGE (2260 2060);
FORCEPROP 2 LASTPIN (2250 2000) $PN 250
J 0
(2260 2010);
DISPLAY 0.617021 (2260 2010);
PAINT ORANGE (2260 2010);
FORCEPROP 2 LASTPIN (2250 1950) $PN 252
J 0
(2260 1960);
DISPLAY 0.617021 (2260 1960);
PAINT ORANGE (2260 1960);
FORCEPROP 2 LASTPIN (2250 1900) $PN 254
J 0
(2260 1910);
DISPLAY 0.617021 (2260 1910);
PAINT ORANGE (2260 1910);
FORCEPROP 2 LASTPIN (2250 1850) $PN 257
J 0
(2260 1860);
DISPLAY 0.617021 (2260 1860);
PAINT ORANGE (2260 1860);
FORCEPROP 2 LASTPIN (2250 1800) $PN 259
J 0
(2260 1810);
DISPLAY 0.617021 (2260 1810);
PAINT ORANGE (2260 1810);
FORCEPROP 2 LASTPIN (2250 1750) $PN 261
J 0
(2260 1760);
DISPLAY 0.617021 (2260 1760);
PAINT ORANGE (2260 1760);
FORCEPROP 2 LASTPIN (2250 1700) $PN 263
J 0
(2260 1710);
DISPLAY 0.617021 (2260 1710);
PAINT ORANGE (2260 1710);
FORCEPROP 2 LASTPIN (2250 1650) $PN 265
J 0
(2260 1660);
DISPLAY 0.617021 (2260 1660);
PAINT ORANGE (2260 1660);
FORCEPROP 2 LASTPIN (2250 1600) $PN 268
J 0
(2260 1610);
DISPLAY 0.617021 (2260 1610);
PAINT ORANGE (2260 1610);
FORCEPROP 2 LASTPIN (2250 1550) $PN 270
J 0
(2260 1560);
DISPLAY 0.617021 (2260 1560);
PAINT ORANGE (2260 1560);
FORCEPROP 2 LASTPIN (2250 1500) $PN 272
J 0
(2260 1510);
DISPLAY 0.617021 (2260 1510);
PAINT ORANGE (2260 1510);
FORCEPROP 2 LASTPIN (2250 1450) $PN 274
J 0
(2260 1460);
DISPLAY 0.617021 (2260 1460);
PAINT ORANGE (2260 1460);
FORCEPROP 2 LASTPIN (2250 1400) $PN 276
J 0
(2260 1410);
DISPLAY 0.617021 (2260 1410);
PAINT ORANGE (2260 1410);
FORCEPROP 2 LASTPIN (2250 1350) $PN 279
J 0
(2260 1360);
DISPLAY 0.617021 (2260 1360);
PAINT ORANGE (2260 1360);
FORCEPROP 2 LASTPIN (2250 1300) $PN 281
J 0
(2260 1310);
DISPLAY 0.617021 (2260 1310);
PAINT ORANGE (2260 1310);
FORCEPROP 2 LASTPIN (2250 1250) $PN 283
J 0
(2260 1260);
DISPLAY 0.617021 (2260 1260);
PAINT ORANGE (2260 1260);
FORCEPROP 2 LASTPIN (2250 3200) $PN 162
J 0
(2260 3210);
DISPLAY 0.617021 (2260 3210);
PAINT ORANGE (2260 3210);
FORCEPROP 2 LASTPIN (1250 3100) $PN 22
J 2
(1240 3110);
DISPLAY 0.617021 (1240 3110);
PAINT ORANGE (1240 3110);
FORCEPROP 2 LASTPIN (2250 2900) $PN 176
J 0
(2260 2910);
DISPLAY 0.617021 (2260 2910);
PAINT ORANGE (2260 2910);
FORCEPROP 1 LAST PACK_TYPE PIP
J 0
(1300 3850);
PAINT SKYBLUE (1300 3850);
DISPLAY INVISIBLE (1300 3850);
FORCEPROP 2 LAST BOM_COST MEM
J 0
(1750 2400);
PAINT ORANGE (1750 2400);
DISPLAY INVISIBLE (1750 2400);
FORCEPROP 2 LAST CDS_LIB mstr_sconn
J 0
(1750 2400);
PAINT ORANGE (1750 2400);
DISPLAY INVISIBLE (1750 2400);
FORCEPROP 2 LAST SEC_TYPE PIP
J 0
(1300 3850);
DISPLAY 1.021277 (1300 3850);
PAINT ORANGE (1300 3850);
DISPLAY INVISIBLE (1300 3850);
FORCEPROP 2 LAST SEC 3
J 0
(1300 3850);
DISPLAY 0.680851 (1300 3850);
PAINT MONO (1300 3850);
DISPLAY INVISIBLE (1300 3850);
FORCEPROP 2 LAST CDS_LOCATION J1G3
J 0
(1300 3800);
DISPLAY 0.617021 (1300 3800);
PAINT AQUA (1300 3800);
DISPLAY INVISIBLE (1300 3800);
FORCEPROP 1 LAST PATH I185
J 0
(1750 3750);
PAINT GREEN (1750 3750);
DISPLAY INVISIBLE (1750 3750);
FORCEPROP 2 LAST ROOM DDR4_CH_J
J 0
(1750 2400);
PAINT ORANGE (1750 2400);
DISPLAY INVISIBLE (1750 2400);
FORCEADD SCONN288_H44441004..1
(-2550 3150);
FORCEPROP 1 LAST LOCATION J1G3
J 0
(-3000 5050);
DISPLAY 0.617021 (-3000 5050);
PAINT AQUA (-3000 5050);
FORCEPROP 1 LAST PART_NUMBER H44441-004
J 0
(-3000 1150);
DISPLAY 0.617021 (-3000 1150);
PAINT BLUE (-3000 1150);
FORCEPROP 2 LASTPIN (-3050 1650) $PN 146
J 2
(-3060 1660);
DISPLAY 0.617021 (-3060 1660);
PAINT ORANGE (-3060 1660);
FORCEPROP 2 LASTPIN (-3050 2000) $PN 284
J 2
(-3060 2010);
DISPLAY 0.617021 (-3060 2010);
PAINT ORANGE (-3060 2010);
FORCEPROP 2 LASTPIN (-3050 1800) $PN 285
J 2
(-3060 1810);
DISPLAY 0.617021 (-3060 1810);
PAINT ORANGE (-3060 1810);
FORCEPROP 2 LASTPIN (-3050 1750) $PN 141
J 2
(-3060 1760);
DISPLAY 0.617021 (-3060 1760);
PAINT ORANGE (-3060 1760);
FORCEPROP 2 LASTPIN (-3050 1350) $PN 230
J 2
(-3060 1360);
DISPLAY 0.617021 (-3060 1360);
PAINT ORANGE (-3060 1360);
FORCEPROP 2 LASTPIN (-3050 1950) $PN 238
J 2
(-3060 1960);
DISPLAY 0.617021 (-3060 1960);
PAINT ORANGE (-3060 1960);
FORCEPROP 2 LASTPIN (-3050 1900) $PN 140
J 2
(-3060 1910);
DISPLAY 0.617021 (-3060 1910);
PAINT ORANGE (-3060 1910);
FORCEPROP 2 LASTPIN (-3050 1850) $PN 139
J 2
(-3060 1860);
DISPLAY 0.617021 (-3060 1860);
PAINT ORANGE (-3060 1860);
FORCEPROP 2 LASTPIN (-3050 3300) $PN 237
J 2
(-3060 3310);
DISPLAY 0.617021 (-3060 3310);
PAINT ORANGE (-3060 3310);
FORCEPROP 2 LASTPIN (-3050 3250) $PN 93
J 2
(-3060 3260);
DISPLAY 0.617021 (-3060 3260);
PAINT ORANGE (-3060 3260);
FORCEPROP 2 LASTPIN (-3050 3200) $PN 89
J 2
(-3060 3210);
DISPLAY 0.617021 (-3060 3210);
PAINT ORANGE (-3060 3210);
FORCEPROP 2 LASTPIN (-3050 3150) $PN 84
J 2
(-3060 3160);
DISPLAY 0.617021 (-3060 3160);
PAINT ORANGE (-3060 3160);
FORCEPROP 2 LASTPIN (-3050 1550) $PN 144
J 2
(-3060 1560);
DISPLAY 0.617021 (-3060 1560);
PAINT ORANGE (-3060 1560);
FORCEPROP 2 LASTPIN (-3050 1500) $PN 227
J 2
(-3060 1510);
DISPLAY 0.617021 (-3060 1510);
PAINT ORANGE (-3060 1510);
FORCEPROP 2 LASTPIN (-3050 1450) $PN 205
J 2
(-3060 1460);
DISPLAY 0.617021 (-3060 1460);
PAINT ORANGE (-3060 1460);
FORCEPROP 2 LASTPIN (-3050 2250) $PN 58
J 2
(-3060 2260);
DISPLAY 0.617021 (-3060 2260);
PAINT ORANGE (-3060 2260);
FORCEPROP 2 LASTPIN (-3050 2300) $PN 222
J 2
(-3060 2310);
DISPLAY 0.617021 (-3060 2310);
PAINT ORANGE (-3060 2310);
FORCEPROP 2 LASTPIN (-3050 2900) $PN 91
J 2
(-3060 2910);
DISPLAY 0.617021 (-3060 2910);
PAINT ORANGE (-3060 2910);
FORCEPROP 2 LASTPIN (-3050 2850) $PN 87
J 2
(-3060 2860);
DISPLAY 0.617021 (-3060 2860);
PAINT ORANGE (-3060 2860);
FORCEPROP 2 LASTPIN (-3050 2200) $PN 78
J 2
(-3060 2210);
DISPLAY 0.617021 (-3060 2210);
PAINT ORANGE (-3060 2210);
FORCEPROP 2 LASTPIN (-2050 4800) $PN 280
J 0
(-2040 4810);
DISPLAY 0.617021 (-2040 4810);
PAINT ORANGE (-2040 4810);
FORCEPROP 2 LASTPIN (-2050 4750) $PN 135
J 0
(-2040 4760);
DISPLAY 0.617021 (-2040 4760);
PAINT ORANGE (-2040 4760);
FORCEPROP 2 LASTPIN (-2050 4700) $PN 273
J 0
(-2040 4710);
DISPLAY 0.617021 (-2040 4710);
PAINT ORANGE (-2040 4710);
FORCEPROP 2 LASTPIN (-2050 4650) $PN 128
J 0
(-2040 4660);
DISPLAY 0.617021 (-2040 4660);
PAINT ORANGE (-2040 4660);
FORCEPROP 2 LASTPIN (-2050 4600) $PN 282
J 0
(-2040 4610);
DISPLAY 0.617021 (-2040 4610);
PAINT ORANGE (-2040 4610);
FORCEPROP 2 LASTPIN (-2050 4550) $PN 137
J 0
(-2040 4560);
DISPLAY 0.617021 (-2040 4560);
PAINT ORANGE (-2040 4560);
FORCEPROP 2 LASTPIN (-2050 4500) $PN 275
J 0
(-2040 4510);
DISPLAY 0.617021 (-2040 4510);
PAINT ORANGE (-2040 4510);
FORCEPROP 2 LASTPIN (-2050 4450) $PN 130
J 0
(-2040 4460);
DISPLAY 0.617021 (-2040 4460);
PAINT ORANGE (-2040 4460);
FORCEPROP 2 LASTPIN (-2050 4400) $PN 269
J 0
(-2040 4410);
DISPLAY 0.617021 (-2040 4410);
PAINT ORANGE (-2040 4410);
FORCEPROP 2 LASTPIN (-2050 4350) $PN 124
J 0
(-2040 4360);
DISPLAY 0.617021 (-2040 4360);
PAINT ORANGE (-2040 4360);
FORCEPROP 2 LASTPIN (-2050 4300) $PN 262
J 0
(-2040 4310);
DISPLAY 0.617021 (-2040 4310);
PAINT ORANGE (-2040 4310);
FORCEPROP 2 LASTPIN (-2050 4250) $PN 117
J 0
(-2040 4260);
DISPLAY 0.617021 (-2040 4260);
PAINT ORANGE (-2040 4260);
FORCEPROP 2 LASTPIN (-2050 4200) $PN 271
J 0
(-2040 4210);
DISPLAY 0.617021 (-2040 4210);
PAINT ORANGE (-2040 4210);
FORCEPROP 2 LASTPIN (-2050 4150) $PN 126
J 0
(-2040 4160);
DISPLAY 0.617021 (-2040 4160);
PAINT ORANGE (-2040 4160);
FORCEPROP 2 LASTPIN (-2050 4100) $PN 264
J 0
(-2040 4110);
DISPLAY 0.617021 (-2040 4110);
PAINT ORANGE (-2040 4110);
FORCEPROP 2 LASTPIN (-2050 4050) $PN 119
J 0
(-2040 4060);
DISPLAY 0.617021 (-2040 4060);
PAINT ORANGE (-2040 4060);
FORCEPROP 2 LASTPIN (-2050 4000) $PN 258
J 0
(-2040 4010);
DISPLAY 0.617021 (-2040 4010);
PAINT ORANGE (-2040 4010);
FORCEPROP 2 LASTPIN (-2050 3950) $PN 113
J 0
(-2040 3960);
DISPLAY 0.617021 (-2040 3960);
PAINT ORANGE (-2040 3960);
FORCEPROP 2 LASTPIN (-2050 3900) $PN 251
J 0
(-2040 3910);
DISPLAY 0.617021 (-2040 3910);
PAINT ORANGE (-2040 3910);
FORCEPROP 2 LASTPIN (-2050 3850) $PN 106
J 0
(-2040 3860);
DISPLAY 0.617021 (-2040 3860);
PAINT ORANGE (-2040 3860);
FORCEPROP 2 LASTPIN (-2050 3800) $PN 260
J 0
(-2040 3810);
DISPLAY 0.617021 (-2040 3810);
PAINT ORANGE (-2040 3810);
FORCEPROP 2 LASTPIN (-2050 3750) $PN 115
J 0
(-2040 3760);
DISPLAY 0.617021 (-2040 3760);
PAINT ORANGE (-2040 3760);
FORCEPROP 2 LASTPIN (-2050 3700) $PN 253
J 0
(-2040 3710);
DISPLAY 0.617021 (-2040 3710);
PAINT ORANGE (-2040 3710);
FORCEPROP 2 LASTPIN (-2050 3650) $PN 108
J 0
(-2040 3660);
DISPLAY 0.617021 (-2040 3660);
PAINT ORANGE (-2040 3660);
FORCEPROP 2 LASTPIN (-2050 3600) $PN 247
J 0
(-2040 3610);
DISPLAY 0.617021 (-2040 3610);
PAINT ORANGE (-2040 3610);
FORCEPROP 2 LASTPIN (-2050 3550) $PN 102
J 0
(-2040 3560);
DISPLAY 0.617021 (-2040 3560);
PAINT ORANGE (-2040 3560);
FORCEPROP 2 LASTPIN (-2050 3500) $PN 240
J 0
(-2040 3510);
DISPLAY 0.617021 (-2040 3510);
PAINT ORANGE (-2040 3510);
FORCEPROP 2 LASTPIN (-2050 3450) $PN 95
J 0
(-2040 3460);
DISPLAY 0.617021 (-2040 3460);
PAINT ORANGE (-2040 3460);
FORCEPROP 2 LASTPIN (-2050 3350) $PN 104
J 0
(-2040 3360);
DISPLAY 0.617021 (-2040 3360);
PAINT ORANGE (-2040 3360);
FORCEPROP 2 LASTPIN (-2050 3300) $PN 242
J 0
(-2040 3310);
DISPLAY 0.617021 (-2040 3310);
PAINT ORANGE (-2040 3310);
FORCEPROP 2 LASTPIN (-2050 3250) $PN 97
J 0
(-2040 3260);
DISPLAY 0.617021 (-2040 3260);
PAINT ORANGE (-2040 3260);
FORCEPROP 2 LASTPIN (-2050 3200) $PN 188
J 0
(-2040 3210);
DISPLAY 0.617021 (-2040 3210);
PAINT ORANGE (-2040 3210);
FORCEPROP 2 LASTPIN (-2050 3150) $PN 43
J 0
(-2040 3160);
DISPLAY 0.617021 (-2040 3160);
PAINT ORANGE (-2040 3160);
FORCEPROP 2 LASTPIN (-2050 3100) $PN 181
J 0
(-2040 3110);
DISPLAY 0.617021 (-2040 3110);
PAINT ORANGE (-2040 3110);
FORCEPROP 2 LASTPIN (-2050 3050) $PN 36
J 0
(-2040 3060);
DISPLAY 0.617021 (-2040 3060);
PAINT ORANGE (-2040 3060);
FORCEPROP 2 LASTPIN (-2050 3000) $PN 190
J 0
(-2040 3010);
DISPLAY 0.617021 (-2040 3010);
PAINT ORANGE (-2040 3010);
FORCEPROP 2 LASTPIN (-2050 2950) $PN 45
J 0
(-2040 2960);
DISPLAY 0.617021 (-2040 2960);
PAINT ORANGE (-2040 2960);
FORCEPROP 2 LASTPIN (-2050 2900) $PN 183
J 0
(-2040 2910);
DISPLAY 0.617021 (-2040 2910);
PAINT ORANGE (-2040 2910);
FORCEPROP 2 LASTPIN (-2050 2800) $PN 177
J 0
(-2040 2810);
DISPLAY 0.617021 (-2040 2810);
PAINT ORANGE (-2040 2810);
FORCEPROP 2 LASTPIN (-2050 2750) $PN 32
J 0
(-2040 2760);
DISPLAY 0.617021 (-2040 2760);
PAINT ORANGE (-2040 2760);
FORCEPROP 2 LASTPIN (-2050 2700) $PN 170
J 0
(-2040 2710);
DISPLAY 0.617021 (-2040 2710);
PAINT ORANGE (-2040 2710);
FORCEPROP 2 LASTPIN (-2050 2650) $PN 25
J 0
(-2040 2660);
DISPLAY 0.617021 (-2040 2660);
PAINT ORANGE (-2040 2660);
FORCEPROP 2 LASTPIN (-2050 2600) $PN 179
J 0
(-2040 2610);
DISPLAY 0.617021 (-2040 2610);
PAINT ORANGE (-2040 2610);
FORCEPROP 2 LASTPIN (-2050 2550) $PN 34
J 0
(-2040 2560);
DISPLAY 0.617021 (-2040 2560);
PAINT ORANGE (-2040 2560);
FORCEPROP 2 LASTPIN (-2050 2500) $PN 172
J 0
(-2040 2510);
DISPLAY 0.617021 (-2040 2510);
PAINT ORANGE (-2040 2510);
FORCEPROP 2 LASTPIN (-2050 2450) $PN 27
J 0
(-2040 2460);
DISPLAY 0.617021 (-2040 2460);
PAINT ORANGE (-2040 2460);
FORCEPROP 2 LASTPIN (-2050 2400) $PN 166
J 0
(-2040 2410);
DISPLAY 0.617021 (-2040 2410);
PAINT ORANGE (-2040 2410);
FORCEPROP 2 LASTPIN (-2050 2350) $PN 21
J 0
(-2040 2360);
DISPLAY 0.617021 (-2040 2360);
PAINT ORANGE (-2040 2360);
FORCEPROP 2 LASTPIN (-2050 2300) $PN 159
J 0
(-2040 2310);
DISPLAY 0.617021 (-2040 2310);
PAINT ORANGE (-2040 2310);
FORCEPROP 2 LASTPIN (-2050 2250) $PN 14
J 0
(-2040 2260);
DISPLAY 0.617021 (-2040 2260);
PAINT ORANGE (-2040 2260);
FORCEPROP 2 LASTPIN (-2050 2200) $PN 168
J 0
(-2040 2210);
DISPLAY 0.617021 (-2040 2210);
PAINT ORANGE (-2040 2210);
FORCEPROP 2 LASTPIN (-2050 2150) $PN 23
J 0
(-2040 2160);
DISPLAY 0.617021 (-2040 2160);
PAINT ORANGE (-2040 2160);
FORCEPROP 2 LASTPIN (-2050 2100) $PN 161
J 0
(-2040 2110);
DISPLAY 0.617021 (-2040 2110);
PAINT ORANGE (-2040 2110);
FORCEPROP 2 LASTPIN (-2050 2050) $PN 16
J 0
(-2040 2060);
DISPLAY 0.617021 (-2040 2060);
PAINT ORANGE (-2040 2060);
FORCEPROP 2 LASTPIN (-2050 2000) $PN 155
J 0
(-2040 2010);
DISPLAY 0.617021 (-2040 2010);
PAINT ORANGE (-2040 2010);
FORCEPROP 2 LASTPIN (-2050 1950) $PN 10
J 0
(-2040 1960);
DISPLAY 0.617021 (-2040 1960);
PAINT ORANGE (-2040 1960);
FORCEPROP 2 LASTPIN (-2050 1900) $PN 148
J 0
(-2040 1910);
DISPLAY 0.617021 (-2040 1910);
PAINT ORANGE (-2040 1910);
FORCEPROP 2 LASTPIN (-2050 1850) $PN 3
J 0
(-2040 1860);
DISPLAY 0.617021 (-2040 1860);
PAINT ORANGE (-2040 1860);
FORCEPROP 2 LASTPIN (-2050 1800) $PN 157
J 0
(-2040 1810);
DISPLAY 0.617021 (-2040 1810);
PAINT ORANGE (-2040 1810);
FORCEPROP 2 LASTPIN (-2050 1750) $PN 12
J 0
(-2040 1760);
DISPLAY 0.617021 (-2040 1760);
PAINT ORANGE (-2040 1760);
FORCEPROP 2 LASTPIN (-2050 1700) $PN 150
J 0
(-2040 1710);
DISPLAY 0.617021 (-2040 1710);
PAINT ORANGE (-2040 1710);
FORCEPROP 2 LASTPIN (-2050 1650) $PN 5
J 0
(-2040 1660);
DISPLAY 0.617021 (-2040 1660);
PAINT ORANGE (-2040 1660);
FORCEPROP 2 LASTPIN (-3050 3050) $PN 203
J 2
(-3060 3060);
DISPLAY 0.617021 (-3060 3060);
PAINT ORANGE (-3060 3060);
FORCEPROP 2 LASTPIN (-3050 3000) $PN 60
J 2
(-3060 3010);
DISPLAY 0.617021 (-3060 3010);
PAINT ORANGE (-3060 3010);
FORCEPROP 2 LASTPIN (-3050 3600) $PN 218
J 2
(-3060 3610);
DISPLAY 0.617021 (-3060 3610);
PAINT ORANGE (-3060 3610);
FORCEPROP 2 LASTPIN (-3050 3550) $PN 219
J 2
(-3060 3560);
DISPLAY 0.617021 (-3060 3560);
PAINT ORANGE (-3060 3560);
FORCEPROP 2 LASTPIN (-3050 3500) $PN 74
J 2
(-3060 3510);
DISPLAY 0.617021 (-3060 3510);
PAINT ORANGE (-3060 3510);
FORCEPROP 2 LASTPIN (-3050 3450) $PN 75
J 2
(-3060 3460);
DISPLAY 0.617021 (-3060 3460);
PAINT ORANGE (-3060 3460);
FORCEPROP 2 LASTPIN (-3050 2750) $PN 199
J 2
(-3060 2760);
DISPLAY 0.617021 (-3060 2760);
PAINT ORANGE (-3060 2760);
FORCEPROP 2 LASTPIN (-3050 2700) $PN 54
J 2
(-3060 2710);
DISPLAY 0.617021 (-3060 2710);
PAINT ORANGE (-3060 2710);
FORCEPROP 2 LASTPIN (-3050 2650) $PN 192
J 2
(-3060 2660);
DISPLAY 0.617021 (-3060 2660);
PAINT ORANGE (-3060 2660);
FORCEPROP 2 LASTPIN (-3050 2600) $PN 47
J 2
(-3060 2610);
DISPLAY 0.617021 (-3060 2610);
PAINT ORANGE (-3060 2610);
FORCEPROP 2 LASTPIN (-3050 2550) $PN 201
J 2
(-3060 2560);
DISPLAY 0.617021 (-3060 2560);
PAINT ORANGE (-3060 2560);
FORCEPROP 2 LASTPIN (-3050 2500) $PN 56
J 2
(-3060 2510);
DISPLAY 0.617021 (-3060 2510);
PAINT ORANGE (-3060 2510);
FORCEPROP 2 LASTPIN (-3050 2450) $PN 194
J 2
(-3060 2460);
DISPLAY 0.617021 (-3060 2460);
PAINT ORANGE (-3060 2460);
FORCEPROP 2 LASTPIN (-3050 2400) $PN 49
J 2
(-3060 2410);
DISPLAY 0.617021 (-3060 2410);
PAINT ORANGE (-3060 2410);
FORCEPROP 2 LASTPIN (-3050 3350) $PN 235
J 2
(-3060 3360);
DISPLAY 0.617021 (-3060 3360);
PAINT ORANGE (-3060 3360);
FORCEPROP 2 LASTPIN (-3050 3750) $PN 207
J 2
(-3060 3760);
DISPLAY 0.617021 (-3060 3760);
PAINT ORANGE (-3060 3760);
FORCEPROP 2 LASTPIN (-3050 3700) $PN 63
J 2
(-3060 3710);
DISPLAY 0.617021 (-3060 3710);
PAINT ORANGE (-3060 3710);
FORCEPROP 2 LASTPIN (-3050 3850) $PN 224
J 2
(-3060 3860);
DISPLAY 0.617021 (-3060 3860);
PAINT ORANGE (-3060 3860);
FORCEPROP 2 LASTPIN (-3050 3800) $PN 81
J 2
(-3060 3810);
DISPLAY 0.617021 (-3060 3810);
PAINT ORANGE (-3060 3810);
FORCEPROP 2 LASTPIN (-3050 2150) $PN 208
J 2
(-3060 2160);
DISPLAY 0.617021 (-3060 2160);
PAINT ORANGE (-3060 2160);
FORCEPROP 2 LASTPIN (-3050 2100) $PN 62
J 2
(-3060 2110);
DISPLAY 0.617021 (-3060 2110);
PAINT ORANGE (-3060 2110);
FORCEPROP 2 LASTPIN (-3050 4800) $PN 234
J 2
(-3060 4810);
DISPLAY 0.617021 (-3060 4810);
PAINT ORANGE (-3060 4810);
FORCEPROP 2 LASTPIN (-3050 4750) $PN 82
J 2
(-3060 4760);
DISPLAY 0.617021 (-3060 4760);
PAINT ORANGE (-3060 4760);
FORCEPROP 2 LASTPIN (-3050 4700) $PN 86
J 2
(-3060 4710);
DISPLAY 0.617021 (-3060 4710);
PAINT ORANGE (-3060 4710);
FORCEPROP 2 LASTPIN (-3050 4650) $PN 228
J 2
(-3060 4660);
DISPLAY 0.617021 (-3060 4660);
PAINT ORANGE (-3060 4660);
FORCEPROP 2 LASTPIN (-3050 4600) $PN 232
J 2
(-3060 4610);
DISPLAY 0.617021 (-3060 4610);
PAINT ORANGE (-3060 4610);
FORCEPROP 2 LASTPIN (-3050 4550) $PN 65
J 2
(-3060 4560);
DISPLAY 0.617021 (-3060 4560);
PAINT ORANGE (-3060 4560);
FORCEPROP 2 LASTPIN (-3050 4500) $PN 210
J 2
(-3060 4510);
DISPLAY 0.617021 (-3060 4510);
PAINT ORANGE (-3060 4510);
FORCEPROP 2 LASTPIN (-3050 4450) $PN 225
J 2
(-3060 4460);
DISPLAY 0.617021 (-3060 4460);
PAINT ORANGE (-3060 4460);
FORCEPROP 2 LASTPIN (-3050 4400) $PN 66
J 2
(-3060 4410);
DISPLAY 0.617021 (-3060 4410);
PAINT ORANGE (-3060 4410);
FORCEPROP 2 LASTPIN (-3050 4350) $PN 68
J 2
(-3060 4360);
DISPLAY 0.617021 (-3060 4360);
PAINT ORANGE (-3060 4360);
FORCEPROP 2 LASTPIN (-3050 4300) $PN 211
J 2
(-3060 4310);
DISPLAY 0.617021 (-3060 4310);
PAINT ORANGE (-3060 4310);
FORCEPROP 2 LASTPIN (-3050 4250) $PN 69
J 2
(-3060 4260);
DISPLAY 0.617021 (-3060 4260);
PAINT ORANGE (-3060 4260);
FORCEPROP 2 LASTPIN (-3050 4200) $PN 213
J 2
(-3060 4210);
DISPLAY 0.617021 (-3060 4210);
PAINT ORANGE (-3060 4210);
FORCEPROP 2 LASTPIN (-3050 4150) $PN 214
J 2
(-3060 4160);
DISPLAY 0.617021 (-3060 4160);
PAINT ORANGE (-3060 4160);
FORCEPROP 2 LASTPIN (-3050 4100) $PN 71
J 2
(-3060 4110);
DISPLAY 0.617021 (-3060 4110);
PAINT ORANGE (-3060 4110);
FORCEPROP 2 LASTPIN (-3050 4050) $PN 216
J 2
(-3060 4060);
DISPLAY 0.617021 (-3060 4060);
PAINT ORANGE (-3060 4060);
FORCEPROP 2 LASTPIN (-3050 4000) $PN 72
J 2
(-3060 4010);
DISPLAY 0.617021 (-3060 4010);
PAINT ORANGE (-3060 4010);
FORCEPROP 2 LASTPIN (-3050 3950) $PN 79
J 2
(-3060 3960);
DISPLAY 0.617021 (-3060 3960);
PAINT ORANGE (-3060 3960);
FORCEPROP 2 LASTPIN (-2050 2850) $PN 38
J 0
(-2040 2860);
DISPLAY 0.617021 (-2040 2860);
PAINT ORANGE (-2040 2860);
FORCEPROP 1 LAST MATERIAL SCONN
J 0
(-3000 5000);
DISPLAY 0.617021 (-3000 5000);
PAINT SKYBLUE (-3000 5000);
FORCEPROP 2 LASTPIN (-2050 3400) $PN 249
J 0
(-2040 3410);
DISPLAY 0.617021 (-2040 3410);
PAINT ORANGE (-2040 3410);
FORCEPROP 1 LAST PACK_TYPE PIP
J 0
(-3000 5100);
PAINT SKYBLUE (-3000 5100);
DISPLAY INVISIBLE (-3000 5100);
FORCEPROP 2 LAST BOM_COST MEM
J 0
(-2550 3150);
PAINT ORANGE (-2550 3150);
DISPLAY INVISIBLE (-2550 3150);
FORCEPROP 2 LAST CDS_LIB mstr_sconn
J 0
(-2550 3150);
PAINT ORANGE (-2550 3150);
DISPLAY INVISIBLE (-2550 3150);
FORCEPROP 2 LAST SEC_TYPE PIP
J 0
(-3000 5100);
DISPLAY 1.021277 (-3000 5100);
PAINT ORANGE (-3000 5100);
DISPLAY INVISIBLE (-3000 5100);
FORCEPROP 2 LAST SEC 1
J 0
(-3000 5100);
DISPLAY 0.680851 (-3000 5100);
PAINT MONO (-3000 5100);
DISPLAY INVISIBLE (-3000 5100);
FORCEPROP 2 LAST CDS_LOCATION J1G3
J 0
(-3000 5050);
DISPLAY 0.617021 (-3000 5050);
PAINT AQUA (-3000 5050);
DISPLAY INVISIBLE (-3000 5050);
FORCEPROP 1 LAST PATH I186
J 0
(-2550 5000);
PAINT GREEN (-2550 5000);
DISPLAY INVISIBLE (-2550 5000);
FORCEPROP 2 LAST ROOM DDR4_CH_J
J 0
(-2550 3150);
PAINT ORANGE (-2550 3150);
DISPLAY INVISIBLE (-2550 3150);
FORCEADD P12V_NVDIMM_GHJ..1
(350 2975);
FORCEPROP 3 LASTPIN (350 2925) SIG_NAME P12V_NVDIMM_GHJ\g
J 0
(360 2935);
DISPLAY 0.659574 (360 2935);
PAINT MONO (360 2935);
DISPLAY INVISIBLE (360 2935);
FORCEPROP 1 LAST VOLTAGE 12.0
J 0
(305 2932);
DISPLAY 0.340426 (305 2932);
PAINT SKYBLUE (305 2932);
DISPLAY INVISIBLE (305 2932);
FORCEPROP 2 LAST CDS_LIB mstr_symbols
J 0
(350 2975);
PAINT ORANGE (350 2975);
DISPLAY INVISIBLE (350 2975);
FORCEPROP 1 LAST BODY_TYPE PLUMBING
J 0
(305 2932);
DISPLAY 0.340426 (305 2932);
PAINT GREEN (305 2932);
DISPLAY INVISIBLE (305 2932);
FORCEPROP 1 LAST PATH I187
J 0
(400 3000);
DISPLAY 0.872340 (400 3000);
PAINT AQUA (400 3000);
DISPLAY INVISIBLE (400 3000);
FORCEPROP 1 LAST HDL_POWER P12V_NVDIMM_GHJ
J 1
(350 3025);
DISPLAY 0.872340 (350 3025);
PAINT GREEN (350 3025);
DISPLAY INVISIBLE (350 3025);
FORCEADD OFFPAGE..3
(1550 5200);
FORCEPROP 2 LAST $XR1 82 
J 0
(1854 5200);
DISPLAY 0.638298 (1854 5200);
PAINT MONO (1854 5200);
FORCEPROP 2 LAST $XR0 59 
J 0
(1764 5200);
DISPLAY 0.638298 (1764 5200);
PAINT MONO (1764 5200);
FORCEPROP 2 LAST CDS_LIB mstr_standard
J 0
(1550 5200);
DISPLAY 0.787234 (1550 5200);
PAINT MONO (1550 5200);
DISPLAY INVISIBLE (1550 5200);
FORCEPROP 1 LAST OFFPAGE TRUE
J 0
(1875 5075);
DISPLAY 0.936170 (1875 5075);
PAINT GREEN (1875 5075);
DISPLAY INVISIBLE (1875 5075);
FORCEPROP 1 LAST COMMENT_BODY TRUE
J 0
(1500 5100);
DISPLAY 0.936170 (1500 5100);
PAINT GREEN (1500 5100);
DISPLAY INVISIBLE (1500 5100);
FORCEPROP 2 LAST PATH I2
J 0
(1750 5275);
DISPLAY 0.787234 (1750 5275);
PAINT MONO (1750 5275);
DISPLAY INVISIBLE (1750 5275);
FORCEADD TAP..6
R 2
(850 4300);
FORCEPROP 3 LASTPIN (800 4300) SIG_NAME M_J_DQS_DN<9>
J 0
(810 4310);
DISPLAY 0.659574 (810 4310);
PAINT MONO (810 4310);
DISPLAY INVISIBLE (810 4310);
FORCEPROP 1 LASTPIN (800 4300) BN 9
J 2
(850 4310);
DISPLAY 0.617021 (850 4310);
PAINT PINK (850 4310);
FORCEPROP 2 LAST CDS_LIB mstr_standard
J 0
(850 4300);
DISPLAY 0.787234 (850 4300);
PAINT MONO (850 4300);
DISPLAY INVISIBLE (850 4300);
FORCEPROP 1 LAST BODY_TYPE PLUMBING
J 2
(850 4250);
DISPLAY 1.234043 (850 4250);
PAINT GREEN (850 4250);
DISPLAY INVISIBLE (850 4250);
FORCEPROP 1 LAST HDL_TAP TRUE
J 2
(525 4175);
DISPLAY 1.234043 (525 4175);
PAINT GREEN (525 4175);
DISPLAY INVISIBLE (525 4175);
FORCEPROP 1 LAST PATH I20
J 2
(850 4300);
DISPLAY 0.936170 (850 4300);
PAINT GREEN (850 4300);
DISPLAY INVISIBLE (850 4300);
FORCEADD TAP..6
R 2
(850 4400);
FORCEPROP 3 LASTPIN (800 4400) SIG_NAME M_J_DQS_DN<10>
J 0
(810 4410);
DISPLAY 0.659574 (810 4410);
PAINT MONO (810 4410);
DISPLAY INVISIBLE (810 4410);
FORCEPROP 1 LASTPIN (800 4400) BN 10
J 2
(850 4410);
DISPLAY 0.617021 (850 4410);
PAINT PINK (850 4410);
FORCEPROP 2 LAST CDS_LIB mstr_standard
J 0
(850 4400);
DISPLAY 0.787234 (850 4400);
PAINT MONO (850 4400);
DISPLAY INVISIBLE (850 4400);
FORCEPROP 1 LAST BODY_TYPE PLUMBING
J 2
(850 4350);
DISPLAY 1.234043 (850 4350);
PAINT GREEN (850 4350);
DISPLAY INVISIBLE (850 4350);
FORCEPROP 1 LAST HDL_TAP TRUE
J 2
(525 4275);
DISPLAY 1.234043 (525 4275);
PAINT GREEN (525 4275);
DISPLAY INVISIBLE (525 4275);
FORCEPROP 1 LAST PATH I21
J 2
(850 4400);
DISPLAY 0.936170 (850 4400);
PAINT GREEN (850 4400);
DISPLAY INVISIBLE (850 4400);
FORCEADD TAP..6
R 2
(850 4200);
FORCEPROP 3 LASTPIN (800 4200) SIG_NAME M_J_DQS_DN<8>
J 0
(810 4210);
DISPLAY 0.659574 (810 4210);
PAINT MONO (810 4210);
DISPLAY INVISIBLE (810 4210);
FORCEPROP 1 LASTPIN (800 4200) BN 8
J 2
(850 4210);
DISPLAY 0.617021 (850 4210);
PAINT PINK (850 4210);
FORCEPROP 2 LAST CDS_LIB mstr_standard
J 0
(850 4200);
DISPLAY 0.787234 (850 4200);
PAINT MONO (850 4200);
DISPLAY INVISIBLE (850 4200);
FORCEPROP 1 LAST BODY_TYPE PLUMBING
J 2
(850 4150);
DISPLAY 1.234043 (850 4150);
PAINT GREEN (850 4150);
DISPLAY INVISIBLE (850 4150);
FORCEPROP 1 LAST HDL_TAP TRUE
J 2
(525 4075);
DISPLAY 1.234043 (525 4075);
PAINT GREEN (525 4075);
DISPLAY INVISIBLE (525 4075);
FORCEPROP 1 LAST PATH I22
J 2
(850 4200);
DISPLAY 0.936170 (850 4200);
PAINT GREEN (850 4200);
DISPLAY INVISIBLE (850 4200);
FORCEADD TAP..6
R 2
(850 4100);
FORCEPROP 3 LASTPIN (800 4100) SIG_NAME M_J_DQS_DN<7>
J 0
(810 4110);
DISPLAY 0.659574 (810 4110);
PAINT MONO (810 4110);
DISPLAY INVISIBLE (810 4110);
FORCEPROP 1 LASTPIN (800 4100) BN 7
J 2
(850 4110);
DISPLAY 0.617021 (850 4110);
PAINT PINK (850 4110);
FORCEPROP 2 LAST CDS_LIB mstr_standard
J 0
(850 4100);
DISPLAY 0.787234 (850 4100);
PAINT MONO (850 4100);
DISPLAY INVISIBLE (850 4100);
FORCEPROP 1 LAST BODY_TYPE PLUMBING
J 2
(850 4050);
DISPLAY 1.234043 (850 4050);
PAINT GREEN (850 4050);
DISPLAY INVISIBLE (850 4050);
FORCEPROP 1 LAST HDL_TAP TRUE
J 2
(525 3975);
DISPLAY 1.234043 (525 3975);
PAINT GREEN (525 3975);
DISPLAY INVISIBLE (525 3975);
FORCEPROP 1 LAST PATH I23
J 2
(850 4100);
DISPLAY 0.936170 (850 4100);
PAINT GREEN (850 4100);
DISPLAY INVISIBLE (850 4100);
FORCEADD TAP..6
R 2
(850 4000);
FORCEPROP 3 LASTPIN (800 4000) SIG_NAME M_J_DQS_DN<6>
J 0
(810 4010);
DISPLAY 0.659574 (810 4010);
PAINT MONO (810 4010);
DISPLAY INVISIBLE (810 4010);
FORCEPROP 1 LASTPIN (800 4000) BN 6
J 2
(850 4010);
DISPLAY 0.617021 (850 4010);
PAINT PINK (850 4010);
FORCEPROP 2 LAST CDS_LIB mstr_standard
J 0
(850 4000);
DISPLAY 0.787234 (850 4000);
PAINT MONO (850 4000);
DISPLAY INVISIBLE (850 4000);
FORCEPROP 1 LAST BODY_TYPE PLUMBING
J 2
(850 3950);
DISPLAY 1.234043 (850 3950);
PAINT GREEN (850 3950);
DISPLAY INVISIBLE (850 3950);
FORCEPROP 1 LAST HDL_TAP TRUE
J 2
(525 3875);
DISPLAY 1.234043 (525 3875);
PAINT GREEN (525 3875);
DISPLAY INVISIBLE (525 3875);
FORCEPROP 1 LAST PATH I24
J 2
(850 4000);
DISPLAY 0.936170 (850 4000);
PAINT GREEN (850 4000);
DISPLAY INVISIBLE (850 4000);
FORCEADD TAP..6
R 2
(650 4250);
FORCEPROP 3 LASTPIN (600 4250) SIG_NAME M_J_DQS_DP<8>
J 0
(610 4260);
DISPLAY 0.659574 (610 4260);
PAINT MONO (610 4260);
DISPLAY INVISIBLE (610 4260);
FORCEPROP 1 LASTPIN (600 4250) BN 8
J 2
(650 4260);
DISPLAY 0.617021 (650 4260);
PAINT PINK (650 4260);
FORCEPROP 2 LAST CDS_LIB mstr_standard
J 0
(650 4250);
DISPLAY 0.787234 (650 4250);
PAINT MONO (650 4250);
DISPLAY INVISIBLE (650 4250);
FORCEPROP 1 LAST BODY_TYPE PLUMBING
J 2
(650 4200);
DISPLAY 1.234043 (650 4200);
PAINT GREEN (650 4200);
DISPLAY INVISIBLE (650 4200);
FORCEPROP 1 LAST HDL_TAP TRUE
J 2
(325 4125);
DISPLAY 1.234043 (325 4125);
PAINT GREEN (325 4125);
DISPLAY INVISIBLE (325 4125);
FORCEPROP 1 LAST PATH I25
J 2
(650 4250);
DISPLAY 0.936170 (650 4250);
PAINT GREEN (650 4250);
DISPLAY INVISIBLE (650 4250);
FORCEADD TAP..6
R 2
(650 4350);
FORCEPROP 3 LASTPIN (600 4350) SIG_NAME M_J_DQS_DP<9>
J 0
(610 4360);
DISPLAY 0.659574 (610 4360);
PAINT MONO (610 4360);
DISPLAY INVISIBLE (610 4360);
FORCEPROP 1 LASTPIN (600 4350) BN 9
J 2
(650 4360);
DISPLAY 0.617021 (650 4360);
PAINT PINK (650 4360);
FORCEPROP 2 LAST CDS_LIB mstr_standard
J 0
(650 4350);
DISPLAY 0.787234 (650 4350);
PAINT MONO (650 4350);
DISPLAY INVISIBLE (650 4350);
FORCEPROP 1 LAST BODY_TYPE PLUMBING
J 2
(650 4300);
DISPLAY 1.234043 (650 4300);
PAINT GREEN (650 4300);
DISPLAY INVISIBLE (650 4300);
FORCEPROP 1 LAST HDL_TAP TRUE
J 2
(325 4225);
DISPLAY 1.234043 (325 4225);
PAINT GREEN (325 4225);
DISPLAY INVISIBLE (325 4225);
FORCEPROP 1 LAST PATH I26
J 2
(650 4350);
DISPLAY 0.936170 (650 4350);
PAINT GREEN (650 4350);
DISPLAY INVISIBLE (650 4350);
FORCEADD TAP..6
R 2
(650 4450);
FORCEPROP 3 LASTPIN (600 4450) SIG_NAME M_J_DQS_DP<10>
J 0
(610 4460);
DISPLAY 0.659574 (610 4460);
PAINT MONO (610 4460);
DISPLAY INVISIBLE (610 4460);
FORCEPROP 1 LASTPIN (600 4450) BN 10
J 2
(650 4460);
DISPLAY 0.617021 (650 4460);
PAINT PINK (650 4460);
FORCEPROP 2 LAST CDS_LIB mstr_standard
J 0
(650 4450);
DISPLAY 0.787234 (650 4450);
PAINT MONO (650 4450);
DISPLAY INVISIBLE (650 4450);
FORCEPROP 1 LAST BODY_TYPE PLUMBING
J 2
(650 4400);
DISPLAY 1.234043 (650 4400);
PAINT GREEN (650 4400);
DISPLAY INVISIBLE (650 4400);
FORCEPROP 1 LAST HDL_TAP TRUE
J 2
(325 4325);
DISPLAY 1.234043 (325 4325);
PAINT GREEN (325 4325);
DISPLAY INVISIBLE (325 4325);
FORCEPROP 1 LAST PATH I27
J 2
(650 4450);
DISPLAY 0.936170 (650 4450);
PAINT GREEN (650 4450);
DISPLAY INVISIBLE (650 4450);
FORCEADD TAP..6
R 2
(650 4150);
FORCEPROP 3 LASTPIN (600 4150) SIG_NAME M_J_DQS_DP<7>
J 0
(610 4160);
DISPLAY 0.659574 (610 4160);
PAINT MONO (610 4160);
DISPLAY INVISIBLE (610 4160);
FORCEPROP 1 LASTPIN (600 4150) BN 7
J 2
(650 4160);
DISPLAY 0.617021 (650 4160);
PAINT PINK (650 4160);
FORCEPROP 2 LAST CDS_LIB mstr_standard
J 0
(650 4150);
DISPLAY 0.787234 (650 4150);
PAINT MONO (650 4150);
DISPLAY INVISIBLE (650 4150);
FORCEPROP 1 LAST BODY_TYPE PLUMBING
J 2
(650 4100);
DISPLAY 1.234043 (650 4100);
PAINT GREEN (650 4100);
DISPLAY INVISIBLE (650 4100);
FORCEPROP 1 LAST HDL_TAP TRUE
J 2
(325 4025);
DISPLAY 1.234043 (325 4025);
PAINT GREEN (325 4025);
DISPLAY INVISIBLE (325 4025);
FORCEPROP 1 LAST PATH I28
J 2
(650 4150);
DISPLAY 0.936170 (650 4150);
PAINT GREEN (650 4150);
DISPLAY INVISIBLE (650 4150);
FORCEADD TAP..6
R 2
(650 4050);
FORCEPROP 3 LASTPIN (600 4050) SIG_NAME M_J_DQS_DP<6>
J 0
(610 4060);
DISPLAY 0.659574 (610 4060);
PAINT MONO (610 4060);
DISPLAY INVISIBLE (610 4060);
FORCEPROP 1 LASTPIN (600 4050) BN 6
J 2
(650 4060);
DISPLAY 0.617021 (650 4060);
PAINT PINK (650 4060);
FORCEPROP 2 LAST CDS_LIB mstr_standard
J 0
(650 4050);
DISPLAY 0.787234 (650 4050);
PAINT MONO (650 4050);
DISPLAY INVISIBLE (650 4050);
FORCEPROP 1 LAST BODY_TYPE PLUMBING
J 2
(650 4000);
DISPLAY 1.234043 (650 4000);
PAINT GREEN (650 4000);
DISPLAY INVISIBLE (650 4000);
FORCEPROP 1 LAST HDL_TAP TRUE
J 2
(325 3925);
DISPLAY 1.234043 (325 3925);
PAINT GREEN (325 3925);
DISPLAY INVISIBLE (325 3925);
FORCEPROP 1 LAST PATH I29
J 2
(650 4050);
DISPLAY 0.936170 (650 4050);
PAINT GREEN (650 4050);
DISPLAY INVISIBLE (650 4050);
FORCEADD TAP..6
R 2
(850 5100);
FORCEPROP 3 LASTPIN (800 5100) SIG_NAME M_J_DQS_DN<17>
J 0
(810 5110);
DISPLAY 0.659574 (810 5110);
PAINT MONO (810 5110);
DISPLAY INVISIBLE (810 5110);
FORCEPROP 1 LASTPIN (800 5100) BN 17
J 2
(850 5110);
DISPLAY 0.617021 (850 5110);
PAINT PINK (850 5110);
FORCEPROP 2 LAST CDS_LIB mstr_standard
J 2
(850 5100);
DISPLAY 0.787234 (850 5100);
PAINT MONO (850 5100);
DISPLAY INVISIBLE (850 5100);
FORCEPROP 1 LAST BODY_TYPE PLUMBING
J 2
(850 5050);
DISPLAY 1.234043 (850 5050);
PAINT GREEN (850 5050);
DISPLAY INVISIBLE (850 5050);
FORCEPROP 1 LAST HDL_TAP TRUE
J 2
(525 4975);
DISPLAY 1.234043 (525 4975);
PAINT GREEN (525 4975);
DISPLAY INVISIBLE (525 4975);
FORCEPROP 1 LAST PATH I3
J 2
(850 5100);
DISPLAY 0.936170 (850 5100);
PAINT GREEN (850 5100);
DISPLAY INVISIBLE (850 5100);
FORCEADD TAP..6
R 2
(850 3900);
FORCEPROP 3 LASTPIN (800 3900) SIG_NAME M_J_DQS_DN<5>
J 0
(810 3910);
DISPLAY 0.659574 (810 3910);
PAINT MONO (810 3910);
DISPLAY INVISIBLE (810 3910);
FORCEPROP 1 LASTPIN (800 3900) BN 5
J 2
(850 3910);
DISPLAY 0.617021 (850 3910);
PAINT PINK (850 3910);
FORCEPROP 2 LAST CDS_LIB mstr_standard
J 0
(850 3900);
DISPLAY 0.787234 (850 3900);
PAINT MONO (850 3900);
DISPLAY INVISIBLE (850 3900);
FORCEPROP 1 LAST BODY_TYPE PLUMBING
J 2
(850 3850);
DISPLAY 1.234043 (850 3850);
PAINT GREEN (850 3850);
DISPLAY INVISIBLE (850 3850);
FORCEPROP 1 LAST HDL_TAP TRUE
J 2
(525 3775);
DISPLAY 1.234043 (525 3775);
PAINT GREEN (525 3775);
DISPLAY INVISIBLE (525 3775);
FORCEPROP 1 LAST PATH I30
J 2
(850 3900);
DISPLAY 0.936170 (850 3900);
PAINT GREEN (850 3900);
DISPLAY INVISIBLE (850 3900);
FORCEADD TAP..6
R 2
(850 3800);
FORCEPROP 3 LASTPIN (800 3800) SIG_NAME M_J_DQS_DN<4>
J 0
(810 3810);
DISPLAY 0.659574 (810 3810);
PAINT MONO (810 3810);
DISPLAY INVISIBLE (810 3810);
FORCEPROP 1 LASTPIN (800 3800) BN 4
J 2
(850 3810);
DISPLAY 0.617021 (850 3810);
PAINT PINK (850 3810);
FORCEPROP 2 LAST CDS_LIB mstr_standard
J 0
(850 3800);
DISPLAY 0.787234 (850 3800);
PAINT MONO (850 3800);
DISPLAY INVISIBLE (850 3800);
FORCEPROP 1 LAST BODY_TYPE PLUMBING
J 2
(850 3750);
DISPLAY 1.234043 (850 3750);
PAINT GREEN (850 3750);
DISPLAY INVISIBLE (850 3750);
FORCEPROP 1 LAST HDL_TAP TRUE
J 2
(525 3675);
DISPLAY 1.234043 (525 3675);
PAINT GREEN (525 3675);
DISPLAY INVISIBLE (525 3675);
FORCEPROP 1 LAST PATH I31
J 2
(850 3800);
DISPLAY 0.936170 (850 3800);
PAINT GREEN (850 3800);
DISPLAY INVISIBLE (850 3800);
FORCEADD TAP..6
R 2
(850 3700);
FORCEPROP 3 LASTPIN (800 3700) SIG_NAME M_J_DQS_DN<3>
J 0
(810 3710);
DISPLAY 0.659574 (810 3710);
PAINT MONO (810 3710);
DISPLAY INVISIBLE (810 3710);
FORCEPROP 1 LASTPIN (800 3700) BN 3
J 2
(850 3710);
DISPLAY 0.617021 (850 3710);
PAINT PINK (850 3710);
FORCEPROP 2 LAST CDS_LIB mstr_standard
J 0
(850 3700);
DISPLAY 0.787234 (850 3700);
PAINT MONO (850 3700);
DISPLAY INVISIBLE (850 3700);
FORCEPROP 1 LAST BODY_TYPE PLUMBING
J 2
(850 3650);
DISPLAY 1.234043 (850 3650);
PAINT GREEN (850 3650);
DISPLAY INVISIBLE (850 3650);
FORCEPROP 1 LAST HDL_TAP TRUE
J 2
(525 3575);
DISPLAY 1.234043 (525 3575);
PAINT GREEN (525 3575);
DISPLAY INVISIBLE (525 3575);
FORCEPROP 1 LAST PATH I32
J 2
(850 3700);
DISPLAY 0.936170 (850 3700);
PAINT GREEN (850 3700);
DISPLAY INVISIBLE (850 3700);
FORCEADD TAP..6
R 2
(850 3600);
FORCEPROP 3 LASTPIN (800 3600) SIG_NAME M_J_DQS_DN<2>
J 0
(810 3610);
DISPLAY 0.659574 (810 3610);
PAINT MONO (810 3610);
DISPLAY INVISIBLE (810 3610);
FORCEPROP 1 LASTPIN (800 3600) BN 2
J 2
(850 3610);
DISPLAY 0.617021 (850 3610);
PAINT PINK (850 3610);
FORCEPROP 2 LAST CDS_LIB mstr_standard
J 0
(850 3600);
DISPLAY 0.787234 (850 3600);
PAINT MONO (850 3600);
DISPLAY INVISIBLE (850 3600);
FORCEPROP 1 LAST BODY_TYPE PLUMBING
J 2
(850 3550);
DISPLAY 1.234043 (850 3550);
PAINT GREEN (850 3550);
DISPLAY INVISIBLE (850 3550);
FORCEPROP 1 LAST HDL_TAP TRUE
J 2
(525 3475);
DISPLAY 1.234043 (525 3475);
PAINT GREEN (525 3475);
DISPLAY INVISIBLE (525 3475);
FORCEPROP 1 LAST PATH I33
J 2
(850 3600);
DISPLAY 0.936170 (850 3600);
PAINT GREEN (850 3600);
DISPLAY INVISIBLE (850 3600);
FORCEADD TAP..6
R 2
(850 3500);
FORCEPROP 3 LASTPIN (800 3500) SIG_NAME M_J_DQS_DN<1>
J 0
(810 3510);
DISPLAY 0.659574 (810 3510);
PAINT MONO (810 3510);
DISPLAY INVISIBLE (810 3510);
FORCEPROP 1 LASTPIN (800 3500) BN 1
J 2
(850 3510);
DISPLAY 0.617021 (850 3510);
PAINT PINK (850 3510);
FORCEPROP 2 LAST CDS_LIB mstr_standard
J 0
(850 3500);
DISPLAY 0.787234 (850 3500);
PAINT MONO (850 3500);
DISPLAY INVISIBLE (850 3500);
FORCEPROP 1 LAST BODY_TYPE PLUMBING
J 2
(850 3450);
DISPLAY 1.234043 (850 3450);
PAINT GREEN (850 3450);
DISPLAY INVISIBLE (850 3450);
FORCEPROP 1 LAST HDL_TAP TRUE
J 2
(525 3375);
DISPLAY 1.234043 (525 3375);
PAINT GREEN (525 3375);
DISPLAY INVISIBLE (525 3375);
FORCEPROP 1 LAST PATH I34
J 2
(850 3500);
DISPLAY 0.936170 (850 3500);
PAINT GREEN (850 3500);
DISPLAY INVISIBLE (850 3500);
FORCEADD TAP..6
R 2
(650 3750);
FORCEPROP 3 LASTPIN (600 3750) SIG_NAME M_J_DQS_DP<3>
J 0
(610 3760);
DISPLAY 0.659574 (610 3760);
PAINT MONO (610 3760);
DISPLAY INVISIBLE (610 3760);
FORCEPROP 1 LASTPIN (600 3750) BN 3
J 2
(650 3760);
DISPLAY 0.617021 (650 3760);
PAINT PINK (650 3760);
FORCEPROP 2 LAST CDS_LIB mstr_standard
J 0
(650 3750);
DISPLAY 0.787234 (650 3750);
PAINT MONO (650 3750);
DISPLAY INVISIBLE (650 3750);
FORCEPROP 1 LAST BODY_TYPE PLUMBING
J 2
(650 3700);
DISPLAY 1.234043 (650 3700);
PAINT GREEN (650 3700);
DISPLAY INVISIBLE (650 3700);
FORCEPROP 1 LAST HDL_TAP TRUE
J 2
(325 3625);
DISPLAY 1.234043 (325 3625);
PAINT GREEN (325 3625);
DISPLAY INVISIBLE (325 3625);
FORCEPROP 1 LAST PATH I35
J 2
(650 3750);
DISPLAY 0.936170 (650 3750);
PAINT GREEN (650 3750);
DISPLAY INVISIBLE (650 3750);
FORCEADD TAP..6
R 2
(650 3850);
FORCEPROP 3 LASTPIN (600 3850) SIG_NAME M_J_DQS_DP<4>
J 0
(610 3860);
DISPLAY 0.659574 (610 3860);
PAINT MONO (610 3860);
DISPLAY INVISIBLE (610 3860);
FORCEPROP 1 LASTPIN (600 3850) BN 4
J 2
(650 3860);
DISPLAY 0.617021 (650 3860);
PAINT PINK (650 3860);
FORCEPROP 2 LAST CDS_LIB mstr_standard
J 0
(650 3850);
DISPLAY 0.787234 (650 3850);
PAINT MONO (650 3850);
DISPLAY INVISIBLE (650 3850);
FORCEPROP 1 LAST BODY_TYPE PLUMBING
J 2
(650 3800);
DISPLAY 1.234043 (650 3800);
PAINT GREEN (650 3800);
DISPLAY INVISIBLE (650 3800);
FORCEPROP 1 LAST HDL_TAP TRUE
J 2
(325 3725);
DISPLAY 1.234043 (325 3725);
PAINT GREEN (325 3725);
DISPLAY INVISIBLE (325 3725);
FORCEPROP 1 LAST PATH I36
J 2
(650 3850);
DISPLAY 0.936170 (650 3850);
PAINT GREEN (650 3850);
DISPLAY INVISIBLE (650 3850);
FORCEADD TAP..6
R 2
(650 3950);
FORCEPROP 3 LASTPIN (600 3950) SIG_NAME M_J_DQS_DP<5>
J 0
(610 3960);
DISPLAY 0.659574 (610 3960);
PAINT MONO (610 3960);
DISPLAY INVISIBLE (610 3960);
FORCEPROP 1 LASTPIN (600 3950) BN 5
J 2
(650 3960);
DISPLAY 0.617021 (650 3960);
PAINT PINK (650 3960);
FORCEPROP 2 LAST CDS_LIB mstr_standard
J 0
(650 3950);
DISPLAY 0.787234 (650 3950);
PAINT MONO (650 3950);
DISPLAY INVISIBLE (650 3950);
FORCEPROP 1 LAST BODY_TYPE PLUMBING
J 2
(650 3900);
DISPLAY 1.234043 (650 3900);
PAINT GREEN (650 3900);
DISPLAY INVISIBLE (650 3900);
FORCEPROP 1 LAST HDL_TAP TRUE
J 2
(325 3825);
DISPLAY 1.234043 (325 3825);
PAINT GREEN (325 3825);
DISPLAY INVISIBLE (325 3825);
FORCEPROP 1 LAST PATH I37
J 2
(650 3950);
DISPLAY 0.936170 (650 3950);
PAINT GREEN (650 3950);
DISPLAY INVISIBLE (650 3950);
FORCEADD TAP..6
R 2
(650 3550);
FORCEPROP 3 LASTPIN (600 3550) SIG_NAME M_J_DQS_DP<1>
J 0
(610 3560);
DISPLAY 0.659574 (610 3560);
PAINT MONO (610 3560);
DISPLAY INVISIBLE (610 3560);
FORCEPROP 1 LASTPIN (600 3550) BN 1
J 2
(650 3560);
DISPLAY 0.617021 (650 3560);
PAINT PINK (650 3560);
FORCEPROP 2 LAST CDS_LIB mstr_standard
J 0
(650 3550);
DISPLAY 0.787234 (650 3550);
PAINT MONO (650 3550);
DISPLAY INVISIBLE (650 3550);
FORCEPROP 1 LAST BODY_TYPE PLUMBING
J 2
(650 3500);
DISPLAY 1.234043 (650 3500);
PAINT GREEN (650 3500);
DISPLAY INVISIBLE (650 3500);
FORCEPROP 1 LAST HDL_TAP TRUE
J 2
(325 3425);
DISPLAY 1.234043 (325 3425);
PAINT GREEN (325 3425);
DISPLAY INVISIBLE (325 3425);
FORCEPROP 1 LAST PATH I38
J 2
(650 3550);
DISPLAY 0.936170 (650 3550);
PAINT GREEN (650 3550);
DISPLAY INVISIBLE (650 3550);
FORCEADD TAP..6
R 2
(650 3450);
FORCEPROP 3 LASTPIN (600 3450) SIG_NAME M_J_DQS_DP<0>
J 0
(610 3460);
DISPLAY 0.659574 (610 3460);
PAINT MONO (610 3460);
DISPLAY INVISIBLE (610 3460);
FORCEPROP 1 LASTPIN (600 3450) BN 0
J 2
(650 3460);
DISPLAY 0.617021 (650 3460);
PAINT PINK (650 3460);
FORCEPROP 2 LAST CDS_LIB mstr_standard
J 0
(650 3450);
DISPLAY 0.787234 (650 3450);
PAINT MONO (650 3450);
DISPLAY INVISIBLE (650 3450);
FORCEPROP 1 LAST BODY_TYPE PLUMBING
J 2
(650 3400);
DISPLAY 1.234043 (650 3400);
PAINT GREEN (650 3400);
DISPLAY INVISIBLE (650 3400);
FORCEPROP 1 LAST HDL_TAP TRUE
J 2
(325 3325);
DISPLAY 1.234043 (325 3325);
PAINT GREEN (325 3325);
DISPLAY INVISIBLE (325 3325);
FORCEPROP 1 LAST PATH I39
J 2
(650 3450);
DISPLAY 0.936170 (650 3450);
PAINT GREEN (650 3450);
DISPLAY INVISIBLE (650 3450);
FORCEADD TAP..6
R 2
(850 5000);
FORCEPROP 3 LASTPIN (800 5000) SIG_NAME M_J_DQS_DN<16>
J 0
(810 5010);
DISPLAY 0.659574 (810 5010);
PAINT MONO (810 5010);
DISPLAY INVISIBLE (810 5010);
FORCEPROP 1 LASTPIN (800 5000) BN 16
J 2
(850 5010);
DISPLAY 0.617021 (850 5010);
PAINT PINK (850 5010);
FORCEPROP 2 LAST CDS_LIB mstr_standard
J 0
(850 5000);
DISPLAY 0.787234 (850 5000);
PAINT MONO (850 5000);
DISPLAY INVISIBLE (850 5000);
FORCEPROP 1 LAST BODY_TYPE PLUMBING
J 2
(850 4950);
DISPLAY 1.234043 (850 4950);
PAINT GREEN (850 4950);
DISPLAY INVISIBLE (850 4950);
FORCEPROP 1 LAST HDL_TAP TRUE
J 2
(525 4875);
DISPLAY 1.234043 (525 4875);
PAINT GREEN (525 4875);
DISPLAY INVISIBLE (525 4875);
FORCEPROP 1 LAST PATH I4
J 2
(850 5000);
DISPLAY 0.936170 (850 5000);
PAINT GREEN (850 5000);
DISPLAY INVISIBLE (850 5000);
FORCEADD TAP..6
R 2
(650 3650);
FORCEPROP 3 LASTPIN (600 3650) SIG_NAME M_J_DQS_DP<2>
J 0
(610 3660);
DISPLAY 0.659574 (610 3660);
PAINT MONO (610 3660);
DISPLAY INVISIBLE (610 3660);
FORCEPROP 1 LASTPIN (600 3650) BN 2
J 2
(650 3660);
DISPLAY 0.617021 (650 3660);
PAINT PINK (650 3660);
FORCEPROP 2 LAST CDS_LIB mstr_standard
J 0
(650 3650);
DISPLAY 0.787234 (650 3650);
PAINT MONO (650 3650);
DISPLAY INVISIBLE (650 3650);
FORCEPROP 1 LAST BODY_TYPE PLUMBING
J 2
(650 3600);
DISPLAY 1.234043 (650 3600);
PAINT GREEN (650 3600);
DISPLAY INVISIBLE (650 3600);
FORCEPROP 1 LAST HDL_TAP TRUE
J 2
(325 3525);
DISPLAY 1.234043 (325 3525);
PAINT GREEN (325 3525);
DISPLAY INVISIBLE (325 3525);
FORCEPROP 1 LAST PATH I40
J 2
(650 3650);
DISPLAY 0.936170 (650 3650);
PAINT GREEN (650 3650);
DISPLAY INVISIBLE (650 3650);
FORCEADD TAP..6
R 2
(850 3400);
FORCEPROP 3 LASTPIN (800 3400) SIG_NAME M_J_DQS_DN<0>
J 0
(810 3410);
DISPLAY 0.659574 (810 3410);
PAINT MONO (810 3410);
DISPLAY INVISIBLE (810 3410);
FORCEPROP 1 LASTPIN (800 3400) BN 0
J 2
(850 3410);
DISPLAY 0.617021 (850 3410);
PAINT PINK (850 3410);
FORCEPROP 2 LAST CDS_LIB mstr_standard
J 0
(850 3400);
DISPLAY 0.787234 (850 3400);
PAINT MONO (850 3400);
DISPLAY INVISIBLE (850 3400);
FORCEPROP 1 LAST BODY_TYPE PLUMBING
J 2
(850 3350);
DISPLAY 1.234043 (850 3350);
PAINT GREEN (850 3350);
DISPLAY INVISIBLE (850 3350);
FORCEPROP 1 LAST HDL_TAP TRUE
J 2
(525 3275);
DISPLAY 1.234043 (525 3275);
PAINT GREEN (525 3275);
DISPLAY INVISIBLE (525 3275);
FORCEPROP 1 LAST PATH I41
J 2
(850 3400);
DISPLAY 0.936170 (850 3400);
PAINT GREEN (850 3400);
DISPLAY INVISIBLE (850 3400);
FORCEADD GND..1
R 2
(1050 1100);
FORCEPROP 3 LASTPIN (1050 1150) SIG_NAME GND\g
J 0
(1060 1160);
DISPLAY 0.659574 (1060 1160);
PAINT MONO (1060 1160);
DISPLAY INVISIBLE (1060 1160);
FORCEPROP 1 LAST VOLTAGE 0
J 0
(1050 1100);
PAINT SKYBLUE (1050 1100);
DISPLAY INVISIBLE (1050 1100);
FORCEPROP 2 LAST BOM_COST MEM
J 0
(1050 1105);
PAINT ORANGE (1050 1105);
DISPLAY INVISIBLE (1050 1105);
FORCEPROP 2 LAST CDS_LIB mstr_symbols
J 0
(1050 1100);
DISPLAY 0.787234 (1050 1100);
PAINT MONO (1050 1100);
DISPLAY INVISIBLE (1050 1100);
FORCEPROP 1 LAST SIZE 1B
J 2
(975 1050);
DISPLAY 1.170213 (975 1050);
PAINT GREEN (975 1050);
DISPLAY INVISIBLE (975 1050);
FORCEPROP 1 LAST BODY_TYPE PLUMBING
J 2
(1095 1057);
DISPLAY 0.340426 (1095 1057);
PAINT GREEN (1095 1057);
DISPLAY INVISIBLE (1095 1057);
FORCEPROP 1 LAST PATH I44
J 2
(975 1100);
DISPLAY 0.936170 (975 1100);
PAINT GREEN (975 1100);
DISPLAY INVISIBLE (975 1100);
FORCEPROP 2 LAST ROOM DDR4_CH_J
J 0
(1050 1105);
PAINT ORANGE (1050 1105);
DISPLAY INVISIBLE (1050 1105);
FORCEPROP 1 LAST HDL_POWER GND
J 2
(1050 1250);
DISPLAY 0.553191 (1050 1250);
PAINT GREEN (1050 1250);
DISPLAY INVISIBLE (1050 1250);
FORCEADD OFFPAGE..3
(-1300 4850);
FORCEPROP 2 LAST $XR1 82 
J 0
(-996 4850);
DISPLAY 0.638298 (-996 4850);
PAINT MONO (-996 4850);
FORCEPROP 2 LAST $XR0 59 
J 0
(-1086 4850);
DISPLAY 0.638298 (-1086 4850);
PAINT MONO (-1086 4850);
FORCEPROP 2 LAST CDS_LIB mstr_standard
J 0
(-1300 4850);
DISPLAY 0.787234 (-1300 4850);
PAINT MONO (-1300 4850);
DISPLAY INVISIBLE (-1300 4850);
FORCEPROP 1 LAST OFFPAGE TRUE
J 0
(-975 4725);
DISPLAY 0.936170 (-975 4725);
PAINT GREEN (-975 4725);
DISPLAY INVISIBLE (-975 4725);
FORCEPROP 1 LAST COMMENT_BODY TRUE
J 0
(-1350 4750);
DISPLAY 0.936170 (-1350 4750);
PAINT GREEN (-1350 4750);
DISPLAY INVISIBLE (-1350 4750);
FORCEPROP 2 LAST PATH I45
J 0
(-1100 4925);
DISPLAY 0.787234 (-1100 4925);
PAINT MONO (-1100 4925);
DISPLAY INVISIBLE (-1100 4925);
FORCEADD TAP..6
R 2
(-1800 4800);
FORCEPROP 3 LASTPIN (-1850 4800) SIG_NAME M_J_DQ<62>
J 0
(-1840 4810);
DISPLAY 0.659574 (-1840 4810);
PAINT MONO (-1840 4810);
DISPLAY INVISIBLE (-1840 4810);
FORCEPROP 1 LASTPIN (-1850 4800) BN 62
J 2
(-1800 4810);
DISPLAY 0.617021 (-1800 4810);
PAINT PINK (-1800 4810);
FORCEPROP 2 LAST CDS_LIB mstr_standard
J 2
(-1800 4800);
DISPLAY 0.787234 (-1800 4800);
PAINT MONO (-1800 4800);
DISPLAY INVISIBLE (-1800 4800);
FORCEPROP 1 LAST BODY_TYPE PLUMBING
J 2
(-1800 4750);
DISPLAY 1.234043 (-1800 4750);
PAINT GREEN (-1800 4750);
DISPLAY INVISIBLE (-1800 4750);
FORCEPROP 1 LAST HDL_TAP TRUE
J 2
(-2125 4675);
DISPLAY 1.234043 (-2125 4675);
PAINT GREEN (-2125 4675);
DISPLAY INVISIBLE (-2125 4675);
FORCEPROP 1 LAST PATH I46
J 2
(-1800 4800);
DISPLAY 0.936170 (-1800 4800);
PAINT GREEN (-1800 4800);
DISPLAY INVISIBLE (-1800 4800);
FORCEADD TAP..6
R 2
(-1800 4550);
FORCEPROP 3 LASTPIN (-1850 4550) SIG_NAME M_J_DQ<59>
J 0
(-1840 4560);
DISPLAY 0.659574 (-1840 4560);
PAINT MONO (-1840 4560);
DISPLAY INVISIBLE (-1840 4560);
FORCEPROP 1 LASTPIN (-1850 4550) BN 59
J 2
(-1800 4560);
DISPLAY 0.617021 (-1800 4560);
PAINT PINK (-1800 4560);
FORCEPROP 2 LAST CDS_LIB mstr_standard
J 2
(-1800 4550);
DISPLAY 0.787234 (-1800 4550);
PAINT MONO (-1800 4550);
DISPLAY INVISIBLE (-1800 4550);
FORCEPROP 1 LAST BODY_TYPE PLUMBING
J 2
(-1800 4500);
DISPLAY 1.234043 (-1800 4500);
PAINT GREEN (-1800 4500);
DISPLAY INVISIBLE (-1800 4500);
FORCEPROP 1 LAST HDL_TAP TRUE
J 2
(-2125 4425);
DISPLAY 1.234043 (-2125 4425);
PAINT GREEN (-2125 4425);
DISPLAY INVISIBLE (-2125 4425);
FORCEPROP 1 LAST PATH I47
J 2
(-1800 4550);
DISPLAY 0.936170 (-1800 4550);
PAINT GREEN (-1800 4550);
DISPLAY INVISIBLE (-1800 4550);
FORCEADD TAP..6
R 2
(-1800 4600);
FORCEPROP 3 LASTPIN (-1850 4600) SIG_NAME M_J_DQ<58>
J 0
(-1840 4610);
DISPLAY 0.659574 (-1840 4610);
PAINT MONO (-1840 4610);
DISPLAY INVISIBLE (-1840 4610);
FORCEPROP 1 LASTPIN (-1850 4600) BN 58
J 2
(-1800 4610);
DISPLAY 0.617021 (-1800 4610);
PAINT PINK (-1800 4610);
FORCEPROP 2 LAST CDS_LIB mstr_standard
J 2
(-1800 4600);
DISPLAY 0.787234 (-1800 4600);
PAINT MONO (-1800 4600);
DISPLAY INVISIBLE (-1800 4600);
FORCEPROP 1 LAST BODY_TYPE PLUMBING
J 2
(-1800 4550);
DISPLAY 1.234043 (-1800 4550);
PAINT GREEN (-1800 4550);
DISPLAY INVISIBLE (-1800 4550);
FORCEPROP 1 LAST HDL_TAP TRUE
J 2
(-2125 4475);
DISPLAY 1.234043 (-2125 4475);
PAINT GREEN (-2125 4475);
DISPLAY INVISIBLE (-2125 4475);
FORCEPROP 1 LAST PATH I48
J 2
(-1800 4600);
DISPLAY 0.936170 (-1800 4600);
PAINT GREEN (-1800 4600);
DISPLAY INVISIBLE (-1800 4600);
FORCEADD TAP..6
R 2
(-1800 4700);
FORCEPROP 3 LASTPIN (-1850 4700) SIG_NAME M_J_DQ<60>
J 0
(-1840 4710);
DISPLAY 0.659574 (-1840 4710);
PAINT MONO (-1840 4710);
DISPLAY INVISIBLE (-1840 4710);
FORCEPROP 1 LASTPIN (-1850 4700) BN 60
J 2
(-1800 4710);
DISPLAY 0.617021 (-1800 4710);
PAINT PINK (-1800 4710);
FORCEPROP 2 LAST CDS_LIB mstr_standard
J 2
(-1800 4700);
DISPLAY 0.787234 (-1800 4700);
PAINT MONO (-1800 4700);
DISPLAY INVISIBLE (-1800 4700);
FORCEPROP 1 LAST BODY_TYPE PLUMBING
J 2
(-1800 4650);
DISPLAY 1.234043 (-1800 4650);
PAINT GREEN (-1800 4650);
DISPLAY INVISIBLE (-1800 4650);
FORCEPROP 1 LAST HDL_TAP TRUE
J 2
(-2125 4575);
DISPLAY 1.234043 (-2125 4575);
PAINT GREEN (-2125 4575);
DISPLAY INVISIBLE (-2125 4575);
FORCEPROP 1 LAST PATH I49
J 2
(-1800 4700);
DISPLAY 0.936170 (-1800 4700);
PAINT GREEN (-1800 4700);
DISPLAY INVISIBLE (-1800 4700);
FORCEADD TAP..6
R 2
(650 5150);
FORCEPROP 3 LASTPIN (600 5150) SIG_NAME M_J_DQS_DP<17>
J 0
(610 5160);
DISPLAY 0.659574 (610 5160);
PAINT MONO (610 5160);
DISPLAY INVISIBLE (610 5160);
FORCEPROP 1 LASTPIN (600 5150) BN 17
J 2
(650 5160);
DISPLAY 0.617021 (650 5160);
PAINT PINK (650 5160);
FORCEPROP 2 LAST CDS_LIB mstr_standard
J 2
(650 5150);
DISPLAY 0.787234 (650 5150);
PAINT MONO (650 5150);
DISPLAY INVISIBLE (650 5150);
FORCEPROP 1 LAST BODY_TYPE PLUMBING
J 2
(650 5100);
DISPLAY 1.234043 (650 5100);
PAINT GREEN (650 5100);
DISPLAY INVISIBLE (650 5100);
FORCEPROP 1 LAST HDL_TAP TRUE
J 2
(325 5025);
DISPLAY 1.234043 (325 5025);
PAINT GREEN (325 5025);
DISPLAY INVISIBLE (325 5025);
FORCEPROP 1 LAST PATH I5
J 2
(650 5150);
DISPLAY 0.936170 (650 5150);
PAINT GREEN (650 5150);
DISPLAY INVISIBLE (650 5150);
FORCEADD TAP..6
R 2
(-1800 4650);
FORCEPROP 3 LASTPIN (-1850 4650) SIG_NAME M_J_DQ<61>
J 0
(-1840 4660);
DISPLAY 0.659574 (-1840 4660);
PAINT MONO (-1840 4660);
DISPLAY INVISIBLE (-1840 4660);
FORCEPROP 1 LASTPIN (-1850 4650) BN 61
J 2
(-1800 4660);
DISPLAY 0.617021 (-1800 4660);
PAINT PINK (-1800 4660);
FORCEPROP 2 LAST CDS_LIB mstr_standard
J 2
(-1800 4650);
DISPLAY 0.787234 (-1800 4650);
PAINT MONO (-1800 4650);
DISPLAY INVISIBLE (-1800 4650);
FORCEPROP 1 LAST BODY_TYPE PLUMBING
J 2
(-1800 4600);
DISPLAY 1.234043 (-1800 4600);
PAINT GREEN (-1800 4600);
DISPLAY INVISIBLE (-1800 4600);
FORCEPROP 1 LAST HDL_TAP TRUE
J 2
(-2125 4525);
DISPLAY 1.234043 (-2125 4525);
PAINT GREEN (-2125 4525);
DISPLAY INVISIBLE (-2125 4525);
FORCEPROP 1 LAST PATH I50
J 2
(-1800 4650);
DISPLAY 0.936170 (-1800 4650);
PAINT GREEN (-1800 4650);
DISPLAY INVISIBLE (-1800 4650);
FORCEADD TAP..6
R 2
(-1800 4750);
FORCEPROP 3 LASTPIN (-1850 4750) SIG_NAME M_J_DQ<63>
J 0
(-1840 4760);
DISPLAY 0.659574 (-1840 4760);
PAINT MONO (-1840 4760);
DISPLAY INVISIBLE (-1840 4760);
FORCEPROP 1 LASTPIN (-1850 4750) BN 63
J 2
(-1800 4760);
DISPLAY 0.617021 (-1800 4760);
PAINT PINK (-1800 4760);
FORCEPROP 2 LAST CDS_LIB mstr_standard
J 2
(-1800 4750);
DISPLAY 0.787234 (-1800 4750);
PAINT MONO (-1800 4750);
DISPLAY INVISIBLE (-1800 4750);
FORCEPROP 1 LAST BODY_TYPE PLUMBING
J 2
(-1800 4700);
DISPLAY 1.234043 (-1800 4700);
PAINT GREEN (-1800 4700);
DISPLAY INVISIBLE (-1800 4700);
FORCEPROP 1 LAST HDL_TAP TRUE
J 2
(-2125 4625);
DISPLAY 1.234043 (-2125 4625);
PAINT GREEN (-2125 4625);
DISPLAY INVISIBLE (-2125 4625);
FORCEPROP 1 LAST PATH I51
J 2
(-1800 4750);
DISPLAY 0.936170 (-1800 4750);
PAINT GREEN (-1800 4750);
DISPLAY INVISIBLE (-1800 4750);
FORCEADD TAP..6
R 2
(-1800 4450);
FORCEPROP 3 LASTPIN (-1850 4450) SIG_NAME M_J_DQ<57>
J 0
(-1840 4460);
DISPLAY 0.659574 (-1840 4460);
PAINT MONO (-1840 4460);
DISPLAY INVISIBLE (-1840 4460);
FORCEPROP 1 LASTPIN (-1850 4450) BN 57
J 2
(-1800 4460);
DISPLAY 0.617021 (-1800 4460);
PAINT PINK (-1800 4460);
FORCEPROP 2 LAST CDS_LIB mstr_standard
J 2
(-1800 4450);
DISPLAY 0.787234 (-1800 4450);
PAINT MONO (-1800 4450);
DISPLAY INVISIBLE (-1800 4450);
FORCEPROP 1 LAST BODY_TYPE PLUMBING
J 2
(-1800 4400);
DISPLAY 1.234043 (-1800 4400);
PAINT GREEN (-1800 4400);
DISPLAY INVISIBLE (-1800 4400);
FORCEPROP 1 LAST HDL_TAP TRUE
J 2
(-2125 4325);
DISPLAY 1.234043 (-2125 4325);
PAINT GREEN (-2125 4325);
DISPLAY INVISIBLE (-2125 4325);
FORCEPROP 1 LAST PATH I52
J 2
(-1800 4450);
DISPLAY 0.936170 (-1800 4450);
PAINT GREEN (-1800 4450);
DISPLAY INVISIBLE (-1800 4450);
FORCEADD TAP..6
R 2
(-1800 4400);
FORCEPROP 3 LASTPIN (-1850 4400) SIG_NAME M_J_DQ<54>
J 0
(-1840 4410);
DISPLAY 0.659574 (-1840 4410);
PAINT MONO (-1840 4410);
DISPLAY INVISIBLE (-1840 4410);
FORCEPROP 1 LASTPIN (-1850 4400) BN 54
J 2
(-1800 4410);
DISPLAY 0.617021 (-1800 4410);
PAINT PINK (-1800 4410);
FORCEPROP 2 LAST CDS_LIB mstr_standard
J 2
(-1800 4400);
DISPLAY 0.787234 (-1800 4400);
PAINT MONO (-1800 4400);
DISPLAY INVISIBLE (-1800 4400);
FORCEPROP 1 LAST BODY_TYPE PLUMBING
J 2
(-1800 4350);
DISPLAY 1.234043 (-1800 4350);
PAINT GREEN (-1800 4350);
DISPLAY INVISIBLE (-1800 4350);
FORCEPROP 1 LAST HDL_TAP TRUE
J 2
(-2125 4275);
DISPLAY 1.234043 (-2125 4275);
PAINT GREEN (-2125 4275);
DISPLAY INVISIBLE (-2125 4275);
FORCEPROP 1 LAST PATH I53
J 2
(-1800 4400);
DISPLAY 0.936170 (-1800 4400);
PAINT GREEN (-1800 4400);
DISPLAY INVISIBLE (-1800 4400);
FORCEADD TAP..6
R 2
(-1800 4350);
FORCEPROP 3 LASTPIN (-1850 4350) SIG_NAME M_J_DQ<55>
J 0
(-1840 4360);
DISPLAY 0.659574 (-1840 4360);
PAINT MONO (-1840 4360);
DISPLAY INVISIBLE (-1840 4360);
FORCEPROP 1 LASTPIN (-1850 4350) BN 55
J 2
(-1800 4360);
DISPLAY 0.617021 (-1800 4360);
PAINT PINK (-1800 4360);
FORCEPROP 2 LAST CDS_LIB mstr_standard
J 2
(-1800 4350);
DISPLAY 0.787234 (-1800 4350);
PAINT MONO (-1800 4350);
DISPLAY INVISIBLE (-1800 4350);
FORCEPROP 1 LAST BODY_TYPE PLUMBING
J 2
(-1800 4300);
DISPLAY 1.234043 (-1800 4300);
PAINT GREEN (-1800 4300);
DISPLAY INVISIBLE (-1800 4300);
FORCEPROP 1 LAST HDL_TAP TRUE
J 2
(-2125 4225);
DISPLAY 1.234043 (-2125 4225);
PAINT GREEN (-2125 4225);
DISPLAY INVISIBLE (-2125 4225);
FORCEPROP 1 LAST PATH I54
J 2
(-1800 4350);
DISPLAY 0.936170 (-1800 4350);
PAINT GREEN (-1800 4350);
DISPLAY INVISIBLE (-1800 4350);
FORCEADD TAP..6
R 2
(-1800 4300);
FORCEPROP 3 LASTPIN (-1850 4300) SIG_NAME M_J_DQ<52>
J 0
(-1840 4310);
DISPLAY 0.659574 (-1840 4310);
PAINT MONO (-1840 4310);
DISPLAY INVISIBLE (-1840 4310);
FORCEPROP 1 LASTPIN (-1850 4300) BN 52
J 2
(-1800 4310);
DISPLAY 0.617021 (-1800 4310);
PAINT PINK (-1800 4310);
FORCEPROP 2 LAST CDS_LIB mstr_standard
J 2
(-1800 4300);
DISPLAY 0.787234 (-1800 4300);
PAINT MONO (-1800 4300);
DISPLAY INVISIBLE (-1800 4300);
FORCEPROP 1 LAST BODY_TYPE PLUMBING
J 2
(-1800 4250);
DISPLAY 1.234043 (-1800 4250);
PAINT GREEN (-1800 4250);
DISPLAY INVISIBLE (-1800 4250);
FORCEPROP 1 LAST HDL_TAP TRUE
J 2
(-2125 4175);
DISPLAY 1.234043 (-2125 4175);
PAINT GREEN (-2125 4175);
DISPLAY INVISIBLE (-2125 4175);
FORCEPROP 1 LAST PATH I55
J 2
(-1800 4300);
DISPLAY 0.936170 (-1800 4300);
PAINT GREEN (-1800 4300);
DISPLAY INVISIBLE (-1800 4300);
FORCEADD TAP..6
R 2
(-1800 4500);
FORCEPROP 3 LASTPIN (-1850 4500) SIG_NAME M_J_DQ<56>
J 0
(-1840 4510);
DISPLAY 0.659574 (-1840 4510);
PAINT MONO (-1840 4510);
DISPLAY INVISIBLE (-1840 4510);
FORCEPROP 1 LASTPIN (-1850 4500) BN 56
J 2
(-1800 4510);
DISPLAY 0.617021 (-1800 4510);
PAINT PINK (-1800 4510);
FORCEPROP 2 LAST CDS_LIB mstr_standard
J 2
(-1800 4500);
DISPLAY 0.787234 (-1800 4500);
PAINT MONO (-1800 4500);
DISPLAY INVISIBLE (-1800 4500);
FORCEPROP 1 LAST BODY_TYPE PLUMBING
J 2
(-1800 4450);
DISPLAY 1.234043 (-1800 4450);
PAINT GREEN (-1800 4450);
DISPLAY INVISIBLE (-1800 4450);
FORCEPROP 1 LAST HDL_TAP TRUE
J 2
(-2125 4375);
DISPLAY 1.234043 (-2125 4375);
PAINT GREEN (-2125 4375);
DISPLAY INVISIBLE (-2125 4375);
FORCEPROP 1 LAST PATH I56
J 2
(-1800 4500);
DISPLAY 0.936170 (-1800 4500);
PAINT GREEN (-1800 4500);
DISPLAY INVISIBLE (-1800 4500);
FORCEADD TAP..6
R 2
(-1800 4200);
FORCEPROP 3 LASTPIN (-1850 4200) SIG_NAME M_J_DQ<50>
J 0
(-1840 4210);
DISPLAY 0.659574 (-1840 4210);
PAINT MONO (-1840 4210);
DISPLAY INVISIBLE (-1840 4210);
FORCEPROP 1 LASTPIN (-1850 4200) BN 50
J 2
(-1800 4210);
DISPLAY 0.617021 (-1800 4210);
PAINT PINK (-1800 4210);
FORCEPROP 2 LAST CDS_LIB mstr_standard
J 2
(-1800 4200);
DISPLAY 0.787234 (-1800 4200);
PAINT MONO (-1800 4200);
DISPLAY INVISIBLE (-1800 4200);
FORCEPROP 1 LAST BODY_TYPE PLUMBING
J 2
(-1800 4150);
DISPLAY 1.234043 (-1800 4150);
PAINT GREEN (-1800 4150);
DISPLAY INVISIBLE (-1800 4150);
FORCEPROP 1 LAST HDL_TAP TRUE
J 2
(-2125 4075);
DISPLAY 1.234043 (-2125 4075);
PAINT GREEN (-2125 4075);
DISPLAY INVISIBLE (-2125 4075);
FORCEPROP 1 LAST PATH I57
J 2
(-1800 4200);
DISPLAY 0.936170 (-1800 4200);
PAINT GREEN (-1800 4200);
DISPLAY INVISIBLE (-1800 4200);
FORCEADD TAP..6
R 2
(-1800 4150);
FORCEPROP 3 LASTPIN (-1850 4150) SIG_NAME M_J_DQ<51>
J 0
(-1840 4160);
DISPLAY 0.659574 (-1840 4160);
PAINT MONO (-1840 4160);
DISPLAY INVISIBLE (-1840 4160);
FORCEPROP 1 LASTPIN (-1850 4150) BN 51
J 2
(-1800 4160);
DISPLAY 0.617021 (-1800 4160);
PAINT PINK (-1800 4160);
FORCEPROP 2 LAST CDS_LIB mstr_standard
J 2
(-1800 4150);
DISPLAY 0.787234 (-1800 4150);
PAINT MONO (-1800 4150);
DISPLAY INVISIBLE (-1800 4150);
FORCEPROP 1 LAST BODY_TYPE PLUMBING
J 2
(-1800 4100);
DISPLAY 1.234043 (-1800 4100);
PAINT GREEN (-1800 4100);
DISPLAY INVISIBLE (-1800 4100);
FORCEPROP 1 LAST HDL_TAP TRUE
J 2
(-2125 4025);
DISPLAY 1.234043 (-2125 4025);
PAINT GREEN (-2125 4025);
DISPLAY INVISIBLE (-2125 4025);
FORCEPROP 1 LAST PATH I58
J 2
(-1800 4150);
DISPLAY 0.936170 (-1800 4150);
PAINT GREEN (-1800 4150);
DISPLAY INVISIBLE (-1800 4150);
FORCEADD TAP..6
R 2
(-1800 4100);
FORCEPROP 3 LASTPIN (-1850 4100) SIG_NAME M_J_DQ<48>
J 0
(-1840 4110);
DISPLAY 0.659574 (-1840 4110);
PAINT MONO (-1840 4110);
DISPLAY INVISIBLE (-1840 4110);
FORCEPROP 1 LASTPIN (-1850 4100) BN 48
J 2
(-1800 4110);
DISPLAY 0.617021 (-1800 4110);
PAINT PINK (-1800 4110);
FORCEPROP 2 LAST CDS_LIB mstr_standard
J 2
(-1800 4100);
DISPLAY 0.787234 (-1800 4100);
PAINT MONO (-1800 4100);
DISPLAY INVISIBLE (-1800 4100);
FORCEPROP 1 LAST BODY_TYPE PLUMBING
J 2
(-1800 4050);
DISPLAY 1.234043 (-1800 4050);
PAINT GREEN (-1800 4050);
DISPLAY INVISIBLE (-1800 4050);
FORCEPROP 1 LAST HDL_TAP TRUE
J 2
(-2125 3975);
DISPLAY 1.234043 (-2125 3975);
PAINT GREEN (-2125 3975);
DISPLAY INVISIBLE (-2125 3975);
FORCEPROP 1 LAST PATH I59
J 2
(-1800 4100);
DISPLAY 0.936170 (-1800 4100);
PAINT GREEN (-1800 4100);
DISPLAY INVISIBLE (-1800 4100);
FORCEADD TAP..6
R 2
(650 5050);
FORCEPROP 3 LASTPIN (600 5050) SIG_NAME M_J_DQS_DP<16>
J 0
(610 5060);
DISPLAY 0.659574 (610 5060);
PAINT MONO (610 5060);
DISPLAY INVISIBLE (610 5060);
FORCEPROP 1 LASTPIN (600 5050) BN 16
J 2
(650 5060);
DISPLAY 0.617021 (650 5060);
PAINT PINK (650 5060);
FORCEPROP 2 LAST CDS_LIB mstr_standard
J 0
(650 5050);
DISPLAY 0.787234 (650 5050);
PAINT MONO (650 5050);
DISPLAY INVISIBLE (650 5050);
FORCEPROP 1 LAST BODY_TYPE PLUMBING
J 2
(650 5000);
DISPLAY 1.234043 (650 5000);
PAINT GREEN (650 5000);
DISPLAY INVISIBLE (650 5000);
FORCEPROP 1 LAST HDL_TAP TRUE
J 2
(325 4925);
DISPLAY 1.234043 (325 4925);
PAINT GREEN (325 4925);
DISPLAY INVISIBLE (325 4925);
FORCEPROP 1 LAST PATH I6
J 2
(650 5050);
DISPLAY 0.936170 (650 5050);
PAINT GREEN (650 5050);
DISPLAY INVISIBLE (650 5050);
FORCEADD TAP..6
R 2
(-1800 4050);
FORCEPROP 3 LASTPIN (-1850 4050) SIG_NAME M_J_DQ<49>
J 0
(-1840 4060);
DISPLAY 0.659574 (-1840 4060);
PAINT MONO (-1840 4060);
DISPLAY INVISIBLE (-1840 4060);
FORCEPROP 1 LASTPIN (-1850 4050) BN 49
J 2
(-1800 4060);
DISPLAY 0.617021 (-1800 4060);
PAINT PINK (-1800 4060);
FORCEPROP 2 LAST CDS_LIB mstr_standard
J 2
(-1800 4050);
DISPLAY 0.787234 (-1800 4050);
PAINT MONO (-1800 4050);
DISPLAY INVISIBLE (-1800 4050);
FORCEPROP 1 LAST BODY_TYPE PLUMBING
J 2
(-1800 4000);
DISPLAY 1.234043 (-1800 4000);
PAINT GREEN (-1800 4000);
DISPLAY INVISIBLE (-1800 4000);
FORCEPROP 1 LAST HDL_TAP TRUE
J 2
(-2125 3925);
DISPLAY 1.234043 (-2125 3925);
PAINT GREEN (-2125 3925);
DISPLAY INVISIBLE (-2125 3925);
FORCEPROP 1 LAST PATH I60
J 2
(-1800 4050);
DISPLAY 0.936170 (-1800 4050);
PAINT GREEN (-1800 4050);
DISPLAY INVISIBLE (-1800 4050);
FORCEADD TAP..6
R 2
(-1800 4250);
FORCEPROP 3 LASTPIN (-1850 4250) SIG_NAME M_J_DQ<53>
J 0
(-1840 4260);
DISPLAY 0.659574 (-1840 4260);
PAINT MONO (-1840 4260);
DISPLAY INVISIBLE (-1840 4260);
FORCEPROP 1 LASTPIN (-1850 4250) BN 53
J 2
(-1800 4260);
DISPLAY 0.617021 (-1800 4260);
PAINT PINK (-1800 4260);
FORCEPROP 2 LAST CDS_LIB mstr_standard
J 2
(-1800 4250);
DISPLAY 0.787234 (-1800 4250);
PAINT MONO (-1800 4250);
DISPLAY INVISIBLE (-1800 4250);
FORCEPROP 1 LAST BODY_TYPE PLUMBING
J 2
(-1800 4200);
DISPLAY 1.234043 (-1800 4200);
PAINT GREEN (-1800 4200);
DISPLAY INVISIBLE (-1800 4200);
FORCEPROP 1 LAST HDL_TAP TRUE
J 2
(-2125 4125);
DISPLAY 1.234043 (-2125 4125);
PAINT GREEN (-2125 4125);
DISPLAY INVISIBLE (-2125 4125);
FORCEPROP 1 LAST PATH I61
J 2
(-1800 4250);
DISPLAY 0.936170 (-1800 4250);
PAINT GREEN (-1800 4250);
DISPLAY INVISIBLE (-1800 4250);
FORCEADD TAP..6
R 2
(-1800 3900);
FORCEPROP 3 LASTPIN (-1850 3900) SIG_NAME M_J_DQ<44>
J 0
(-1840 3910);
DISPLAY 0.659574 (-1840 3910);
PAINT MONO (-1840 3910);
DISPLAY INVISIBLE (-1840 3910);
FORCEPROP 1 LASTPIN (-1850 3900) BN 44
J 2
(-1800 3910);
DISPLAY 0.617021 (-1800 3910);
PAINT PINK (-1800 3910);
FORCEPROP 2 LAST CDS_LIB mstr_standard
J 2
(-1800 3900);
DISPLAY 0.787234 (-1800 3900);
PAINT MONO (-1800 3900);
DISPLAY INVISIBLE (-1800 3900);
FORCEPROP 1 LAST BODY_TYPE PLUMBING
J 2
(-1800 3850);
DISPLAY 1.234043 (-1800 3850);
PAINT GREEN (-1800 3850);
DISPLAY INVISIBLE (-1800 3850);
FORCEPROP 1 LAST HDL_TAP TRUE
J 2
(-2125 3775);
DISPLAY 1.234043 (-2125 3775);
PAINT GREEN (-2125 3775);
DISPLAY INVISIBLE (-2125 3775);
FORCEPROP 1 LAST PATH I62
J 2
(-1800 3900);
DISPLAY 0.936170 (-1800 3900);
PAINT GREEN (-1800 3900);
DISPLAY INVISIBLE (-1800 3900);
FORCEADD TAP..6
R 2
(-1800 3850);
FORCEPROP 3 LASTPIN (-1850 3850) SIG_NAME M_J_DQ<45>
J 0
(-1840 3860);
DISPLAY 0.659574 (-1840 3860);
PAINT MONO (-1840 3860);
DISPLAY INVISIBLE (-1840 3860);
FORCEPROP 1 LASTPIN (-1850 3850) BN 45
J 2
(-1800 3860);
DISPLAY 0.617021 (-1800 3860);
PAINT PINK (-1800 3860);
FORCEPROP 2 LAST CDS_LIB mstr_standard
J 2
(-1800 3850);
DISPLAY 0.787234 (-1800 3850);
PAINT MONO (-1800 3850);
DISPLAY INVISIBLE (-1800 3850);
FORCEPROP 1 LAST BODY_TYPE PLUMBING
J 2
(-1800 3800);
DISPLAY 1.234043 (-1800 3800);
PAINT GREEN (-1800 3800);
DISPLAY INVISIBLE (-1800 3800);
FORCEPROP 1 LAST HDL_TAP TRUE
J 2
(-2125 3725);
DISPLAY 1.234043 (-2125 3725);
PAINT GREEN (-2125 3725);
DISPLAY INVISIBLE (-2125 3725);
FORCEPROP 1 LAST PATH I63
J 2
(-1800 3850);
DISPLAY 0.936170 (-1800 3850);
PAINT GREEN (-1800 3850);
DISPLAY INVISIBLE (-1800 3850);
FORCEADD TAP..6
R 2
(-1800 3800);
FORCEPROP 3 LASTPIN (-1850 3800) SIG_NAME M_J_DQ<42>
J 0
(-1840 3810);
DISPLAY 0.659574 (-1840 3810);
PAINT MONO (-1840 3810);
DISPLAY INVISIBLE (-1840 3810);
FORCEPROP 1 LASTPIN (-1850 3800) BN 42
J 2
(-1800 3810);
DISPLAY 0.617021 (-1800 3810);
PAINT PINK (-1800 3810);
FORCEPROP 2 LAST CDS_LIB mstr_standard
J 2
(-1800 3800);
DISPLAY 0.787234 (-1800 3800);
PAINT MONO (-1800 3800);
DISPLAY INVISIBLE (-1800 3800);
FORCEPROP 1 LAST BODY_TYPE PLUMBING
J 2
(-1800 3750);
DISPLAY 1.234043 (-1800 3750);
PAINT GREEN (-1800 3750);
DISPLAY INVISIBLE (-1800 3750);
FORCEPROP 1 LAST HDL_TAP TRUE
J 2
(-2125 3675);
DISPLAY 1.234043 (-2125 3675);
PAINT GREEN (-2125 3675);
DISPLAY INVISIBLE (-2125 3675);
FORCEPROP 1 LAST PATH I64
J 2
(-1800 3800);
DISPLAY 0.936170 (-1800 3800);
PAINT GREEN (-1800 3800);
DISPLAY INVISIBLE (-1800 3800);
FORCEADD TAP..6
R 2
(-1800 3950);
FORCEPROP 3 LASTPIN (-1850 3950) SIG_NAME M_J_DQ<47>
J 0
(-1840 3960);
DISPLAY 0.659574 (-1840 3960);
PAINT MONO (-1840 3960);
DISPLAY INVISIBLE (-1840 3960);
FORCEPROP 1 LASTPIN (-1850 3950) BN 47
J 2
(-1800 3960);
DISPLAY 0.617021 (-1800 3960);
PAINT PINK (-1800 3960);
FORCEPROP 2 LAST CDS_LIB mstr_standard
J 2
(-1800 3950);
DISPLAY 0.787234 (-1800 3950);
PAINT MONO (-1800 3950);
DISPLAY INVISIBLE (-1800 3950);
FORCEPROP 1 LAST BODY_TYPE PLUMBING
J 2
(-1800 3900);
DISPLAY 1.234043 (-1800 3900);
PAINT GREEN (-1800 3900);
DISPLAY INVISIBLE (-1800 3900);
FORCEPROP 1 LAST HDL_TAP TRUE
J 2
(-2125 3825);
DISPLAY 1.234043 (-2125 3825);
PAINT GREEN (-2125 3825);
DISPLAY INVISIBLE (-2125 3825);
FORCEPROP 1 LAST PATH I65
J 2
(-1800 3950);
DISPLAY 0.936170 (-1800 3950);
PAINT GREEN (-1800 3950);
DISPLAY INVISIBLE (-1800 3950);
FORCEADD TAP..6
R 2
(-1800 4000);
FORCEPROP 3 LASTPIN (-1850 4000) SIG_NAME M_J_DQ<46>
J 0
(-1840 4010);
DISPLAY 0.659574 (-1840 4010);
PAINT MONO (-1840 4010);
DISPLAY INVISIBLE (-1840 4010);
FORCEPROP 1 LASTPIN (-1850 4000) BN 46
J 2
(-1800 4010);
DISPLAY 0.617021 (-1800 4010);
PAINT PINK (-1800 4010);
FORCEPROP 2 LAST CDS_LIB mstr_standard
J 2
(-1800 4000);
DISPLAY 0.787234 (-1800 4000);
PAINT MONO (-1800 4000);
DISPLAY INVISIBLE (-1800 4000);
FORCEPROP 1 LAST BODY_TYPE PLUMBING
J 2
(-1800 3950);
DISPLAY 1.234043 (-1800 3950);
PAINT GREEN (-1800 3950);
DISPLAY INVISIBLE (-1800 3950);
FORCEPROP 1 LAST HDL_TAP TRUE
J 2
(-2125 3875);
DISPLAY 1.234043 (-2125 3875);
PAINT GREEN (-2125 3875);
DISPLAY INVISIBLE (-2125 3875);
FORCEPROP 1 LAST PATH I66
J 2
(-1800 4000);
DISPLAY 0.936170 (-1800 4000);
PAINT GREEN (-1800 4000);
DISPLAY INVISIBLE (-1800 4000);
FORCEADD SCONN288_H44441004..2
(-50 4300);
FORCEPROP 1 LAST LOCATION J1G3
J 0
(-450 5400);
DISPLAY 0.617021 (-450 5400);
PAINT AQUA (-450 5400);
FORCEPROP 1 LAST PART_NUMBER H44441-004
J 0
(-450 3200);
DISPLAY 0.617021 (-450 3200);
PAINT BLUE (-450 3200);
FORCEPROP 1 LAST MATERIAL SCONN
J 0
(-450 5350);
DISPLAY 0.617021 (-450 5350);
PAINT SKYBLUE (-450 5350);
FORCEPROP 2 LASTPIN (400 5150) $PN 51
J 0
(410 5160);
DISPLAY 0.617021 (410 5160);
PAINT ORANGE (410 5160);
FORCEPROP 2 LASTPIN (400 5100) $PN 52
J 0
(410 5110);
DISPLAY 0.617021 (410 5110);
PAINT ORANGE (410 5110);
FORCEPROP 2 LASTPIN (400 5050) $PN 132
J 0
(410 5060);
DISPLAY 0.617021 (410 5060);
PAINT ORANGE (410 5060);
FORCEPROP 2 LASTPIN (400 5000) $PN 133
J 0
(410 5010);
DISPLAY 0.617021 (410 5010);
PAINT ORANGE (410 5010);
FORCEPROP 2 LASTPIN (400 4950) $PN 121
J 0
(410 4960);
DISPLAY 0.617021 (410 4960);
PAINT ORANGE (410 4960);
FORCEPROP 2 LASTPIN (400 4900) $PN 122
J 0
(410 4910);
DISPLAY 0.617021 (410 4910);
PAINT ORANGE (410 4910);
FORCEPROP 2 LASTPIN (400 4850) $PN 110
J 0
(410 4860);
DISPLAY 0.617021 (410 4860);
PAINT ORANGE (410 4860);
FORCEPROP 2 LASTPIN (400 4800) $PN 111
J 0
(410 4810);
DISPLAY 0.617021 (410 4810);
PAINT ORANGE (410 4810);
FORCEPROP 2 LASTPIN (400 4750) $PN 99
J 0
(410 4760);
DISPLAY 0.617021 (410 4760);
PAINT ORANGE (410 4760);
FORCEPROP 2 LASTPIN (400 4700) $PN 100
J 0
(410 4710);
DISPLAY 0.617021 (410 4710);
PAINT ORANGE (410 4710);
FORCEPROP 2 LASTPIN (400 4650) $PN 40
J 0
(410 4660);
DISPLAY 0.617021 (410 4660);
PAINT ORANGE (410 4660);
FORCEPROP 2 LASTPIN (400 4600) $PN 41
J 0
(410 4610);
DISPLAY 0.617021 (410 4610);
PAINT ORANGE (410 4610);
FORCEPROP 2 LASTPIN (400 4550) $PN 29
J 0
(410 4560);
DISPLAY 0.617021 (410 4560);
PAINT ORANGE (410 4560);
FORCEPROP 2 LASTPIN (400 4500) $PN 30
J 0
(410 4510);
DISPLAY 0.617021 (410 4510);
PAINT ORANGE (410 4510);
FORCEPROP 2 LASTPIN (400 4450) $PN 18
J 0
(410 4460);
DISPLAY 0.617021 (410 4460);
PAINT ORANGE (410 4460);
FORCEPROP 2 LASTPIN (400 4400) $PN 19
J 0
(410 4410);
DISPLAY 0.617021 (410 4410);
PAINT ORANGE (410 4410);
FORCEPROP 2 LASTPIN (400 4350) $PN 7
J 0
(410 4360);
DISPLAY 0.617021 (410 4360);
PAINT ORANGE (410 4360);
FORCEPROP 2 LASTPIN (400 4300) $PN 8
J 0
(410 4310);
DISPLAY 0.617021 (410 4310);
PAINT ORANGE (410 4310);
FORCEPROP 2 LASTPIN (400 4200) $PN 196
J 0
(410 4210);
DISPLAY 0.617021 (410 4210);
PAINT ORANGE (410 4210);
FORCEPROP 2 LASTPIN (400 4150) $PN 278
J 0
(410 4160);
DISPLAY 0.617021 (410 4160);
PAINT ORANGE (410 4160);
FORCEPROP 2 LASTPIN (400 4100) $PN 277
J 0
(410 4110);
DISPLAY 0.617021 (410 4110);
PAINT ORANGE (410 4110);
FORCEPROP 2 LASTPIN (400 4050) $PN 267
J 0
(410 4060);
DISPLAY 0.617021 (410 4060);
PAINT ORANGE (410 4060);
FORCEPROP 2 LASTPIN (400 4000) $PN 266
J 0
(410 4010);
DISPLAY 0.617021 (410 4010);
PAINT ORANGE (410 4010);
FORCEPROP 2 LASTPIN (400 3950) $PN 256
J 0
(410 3960);
DISPLAY 0.617021 (410 3960);
PAINT ORANGE (410 3960);
FORCEPROP 2 LASTPIN (400 3900) $PN 255
J 0
(410 3910);
DISPLAY 0.617021 (410 3910);
PAINT ORANGE (410 3910);
FORCEPROP 2 LASTPIN (400 3850) $PN 245
J 0
(410 3860);
DISPLAY 0.617021 (410 3860);
PAINT ORANGE (410 3860);
FORCEPROP 2 LASTPIN (400 3800) $PN 244
J 0
(410 3810);
DISPLAY 0.617021 (410 3810);
PAINT ORANGE (410 3810);
FORCEPROP 2 LASTPIN (400 3750) $PN 186
J 0
(410 3760);
DISPLAY 0.617021 (410 3760);
PAINT ORANGE (410 3760);
FORCEPROP 2 LASTPIN (400 3700) $PN 185
J 0
(410 3710);
DISPLAY 0.617021 (410 3710);
PAINT ORANGE (410 3710);
FORCEPROP 2 LASTPIN (400 3600) $PN 174
J 0
(410 3610);
DISPLAY 0.617021 (410 3610);
PAINT ORANGE (410 3610);
FORCEPROP 2 LASTPIN (400 3550) $PN 164
J 0
(410 3560);
DISPLAY 0.617021 (410 3560);
PAINT ORANGE (410 3560);
FORCEPROP 2 LASTPIN (400 3500) $PN 163
J 0
(410 3510);
DISPLAY 0.617021 (410 3510);
PAINT ORANGE (410 3510);
FORCEPROP 2 LASTPIN (400 3450) $PN 153
J 0
(410 3460);
DISPLAY 0.617021 (410 3460);
PAINT ORANGE (410 3460);
FORCEPROP 2 LASTPIN (400 3400) $PN 152
J 0
(410 3410);
DISPLAY 0.617021 (410 3410);
PAINT ORANGE (410 3410);
FORCEPROP 2 LASTPIN (400 3650) $PN 175
J 0
(410 3660);
DISPLAY 0.617021 (410 3660);
PAINT ORANGE (410 3660);
FORCEPROP 2 LASTPIN (400 4250) $PN 197
J 0
(410 4260);
DISPLAY 0.617021 (410 4260);
PAINT ORANGE (410 4260);
FORCEPROP 1 LAST PACK_TYPE PIP
J 0
(-450 5450);
PAINT SKYBLUE (-450 5450);
DISPLAY INVISIBLE (-450 5450);
FORCEPROP 2 LAST BOM_COST MEM
J 0
(-50 4300);
PAINT ORANGE (-50 4300);
DISPLAY INVISIBLE (-50 4300);
FORCEPROP 2 LAST CDS_LIB mstr_sconn
J 0
(-50 4300);
PAINT ORANGE (-50 4300);
DISPLAY INVISIBLE (-50 4300);
FORCEPROP 2 LAST SEC_TYPE PIP
J 0
(-450 5450);
DISPLAY 1.021277 (-450 5450);
PAINT ORANGE (-450 5450);
DISPLAY INVISIBLE (-450 5450);
FORCEPROP 2 LAST SEC 2
J 0
(-450 5450);
DISPLAY 0.680851 (-450 5450);
PAINT MONO (-450 5450);
DISPLAY INVISIBLE (-450 5450);
FORCEPROP 2 LAST CDS_LOCATION J1G3
J 0
(-450 5400);
DISPLAY 0.617021 (-450 5400);
PAINT AQUA (-450 5400);
DISPLAY INVISIBLE (-450 5400);
FORCEPROP 1 LAST PATH I67
J 0
(-50 5350);
PAINT GREEN (-50 5350);
DISPLAY INVISIBLE (-50 5350);
FORCEPROP 2 LAST ROOM DDR4_CH_J
J 0
(-50 4300);
PAINT ORANGE (-50 4300);
DISPLAY INVISIBLE (-50 4300);
FORCEADD TAP..6
R 2
(-1800 3600);
FORCEPROP 3 LASTPIN (-1850 3600) SIG_NAME M_J_DQ<38>
J 0
(-1840 3610);
DISPLAY 0.659574 (-1840 3610);
PAINT MONO (-1840 3610);
DISPLAY INVISIBLE (-1840 3610);
FORCEPROP 1 LASTPIN (-1850 3600) BN 38
J 2
(-1800 3610);
DISPLAY 0.617021 (-1800 3610);
PAINT PINK (-1800 3610);
FORCEPROP 2 LAST CDS_LIB mstr_standard
J 2
(-1800 3600);
DISPLAY 0.787234 (-1800 3600);
PAINT MONO (-1800 3600);
DISPLAY INVISIBLE (-1800 3600);
FORCEPROP 1 LAST BODY_TYPE PLUMBING
J 2
(-1800 3550);
DISPLAY 1.234043 (-1800 3550);
PAINT GREEN (-1800 3550);
DISPLAY INVISIBLE (-1800 3550);
FORCEPROP 1 LAST HDL_TAP TRUE
J 2
(-2125 3475);
DISPLAY 1.234043 (-2125 3475);
PAINT GREEN (-2125 3475);
DISPLAY INVISIBLE (-2125 3475);
FORCEPROP 1 LAST PATH I68
J 2
(-1800 3600);
DISPLAY 0.936170 (-1800 3600);
PAINT GREEN (-1800 3600);
DISPLAY INVISIBLE (-1800 3600);
FORCEADD TAP..6
R 2
(-1800 3650);
FORCEPROP 3 LASTPIN (-1850 3650) SIG_NAME M_J_DQ<41>
J 0
(-1840 3660);
DISPLAY 0.659574 (-1840 3660);
PAINT MONO (-1840 3660);
DISPLAY INVISIBLE (-1840 3660);
FORCEPROP 1 LASTPIN (-1850 3650) BN 41
J 2
(-1800 3660);
DISPLAY 0.617021 (-1800 3660);
PAINT PINK (-1800 3660);
FORCEPROP 2 LAST CDS_LIB mstr_standard
J 2
(-1800 3650);
DISPLAY 0.787234 (-1800 3650);
PAINT MONO (-1800 3650);
DISPLAY INVISIBLE (-1800 3650);
FORCEPROP 1 LAST BODY_TYPE PLUMBING
J 2
(-1800 3600);
DISPLAY 1.234043 (-1800 3600);
PAINT GREEN (-1800 3600);
DISPLAY INVISIBLE (-1800 3600);
FORCEPROP 1 LAST HDL_TAP TRUE
J 2
(-2125 3525);
DISPLAY 1.234043 (-2125 3525);
PAINT GREEN (-2125 3525);
DISPLAY INVISIBLE (-2125 3525);
FORCEPROP 1 LAST PATH I69
J 2
(-1800 3650);
DISPLAY 0.936170 (-1800 3650);
PAINT GREEN (-1800 3650);
DISPLAY INVISIBLE (-1800 3650);
FORCEADD TAP..6
R 2
(850 4800);
FORCEPROP 3 LASTPIN (800 4800) SIG_NAME M_J_DQS_DN<14>
J 0
(810 4810);
DISPLAY 0.659574 (810 4810);
PAINT MONO (810 4810);
DISPLAY INVISIBLE (810 4810);
FORCEPROP 1 LASTPIN (800 4800) BN 14
J 2
(850 4810);
DISPLAY 0.617021 (850 4810);
PAINT PINK (850 4810);
FORCEPROP 2 LAST CDS_LIB mstr_standard
J 0
(850 4800);
DISPLAY 0.787234 (850 4800);
PAINT MONO (850 4800);
DISPLAY INVISIBLE (850 4800);
FORCEPROP 1 LAST BODY_TYPE PLUMBING
J 2
(850 4750);
DISPLAY 1.234043 (850 4750);
PAINT GREEN (850 4750);
DISPLAY INVISIBLE (850 4750);
FORCEPROP 1 LAST HDL_TAP TRUE
J 2
(525 4675);
DISPLAY 1.234043 (525 4675);
PAINT GREEN (525 4675);
DISPLAY INVISIBLE (525 4675);
FORCEPROP 1 LAST PATH I7
J 2
(850 4800);
DISPLAY 0.936170 (850 4800);
PAINT GREEN (850 4800);
DISPLAY INVISIBLE (850 4800);
FORCEADD TAP..6
R 2
(-1800 3550);
FORCEPROP 3 LASTPIN (-1850 3550) SIG_NAME M_J_DQ<39>
J 0
(-1840 3560);
DISPLAY 0.659574 (-1840 3560);
PAINT MONO (-1840 3560);
DISPLAY INVISIBLE (-1840 3560);
FORCEPROP 1 LASTPIN (-1850 3550) BN 39
J 2
(-1800 3560);
DISPLAY 0.617021 (-1800 3560);
PAINT PINK (-1800 3560);
FORCEPROP 2 LAST CDS_LIB mstr_standard
J 2
(-1800 3550);
DISPLAY 0.787234 (-1800 3550);
PAINT MONO (-1800 3550);
DISPLAY INVISIBLE (-1800 3550);
FORCEPROP 1 LAST BODY_TYPE PLUMBING
J 2
(-1800 3500);
DISPLAY 1.234043 (-1800 3500);
PAINT GREEN (-1800 3500);
DISPLAY INVISIBLE (-1800 3500);
FORCEPROP 1 LAST HDL_TAP TRUE
J 2
(-2125 3425);
DISPLAY 1.234043 (-2125 3425);
PAINT GREEN (-2125 3425);
DISPLAY INVISIBLE (-2125 3425);
FORCEPROP 1 LAST PATH I70
J 2
(-1800 3550);
DISPLAY 0.936170 (-1800 3550);
PAINT GREEN (-1800 3550);
DISPLAY INVISIBLE (-1800 3550);
FORCEADD TAP..6
R 2
(-1800 3700);
FORCEPROP 3 LASTPIN (-1850 3700) SIG_NAME M_J_DQ<40>
J 0
(-1840 3710);
DISPLAY 0.659574 (-1840 3710);
PAINT MONO (-1840 3710);
DISPLAY INVISIBLE (-1840 3710);
FORCEPROP 1 LASTPIN (-1850 3700) BN 40
J 2
(-1800 3710);
DISPLAY 0.617021 (-1800 3710);
PAINT PINK (-1800 3710);
FORCEPROP 2 LAST CDS_LIB mstr_standard
J 2
(-1800 3700);
DISPLAY 0.787234 (-1800 3700);
PAINT MONO (-1800 3700);
DISPLAY INVISIBLE (-1800 3700);
FORCEPROP 1 LAST BODY_TYPE PLUMBING
J 2
(-1800 3650);
DISPLAY 1.234043 (-1800 3650);
PAINT GREEN (-1800 3650);
DISPLAY INVISIBLE (-1800 3650);
FORCEPROP 1 LAST HDL_TAP TRUE
J 2
(-2125 3575);
DISPLAY 1.234043 (-2125 3575);
PAINT GREEN (-2125 3575);
DISPLAY INVISIBLE (-2125 3575);
FORCEPROP 1 LAST PATH I71
J 2
(-1800 3700);
DISPLAY 0.936170 (-1800 3700);
PAINT GREEN (-1800 3700);
DISPLAY INVISIBLE (-1800 3700);
FORCEADD TAP..6
R 2
(-1800 3750);
FORCEPROP 3 LASTPIN (-1850 3750) SIG_NAME M_J_DQ<43>
J 0
(-1840 3760);
DISPLAY 0.659574 (-1840 3760);
PAINT MONO (-1840 3760);
DISPLAY INVISIBLE (-1840 3760);
FORCEPROP 1 LASTPIN (-1850 3750) BN 43
J 2
(-1800 3760);
DISPLAY 0.617021 (-1800 3760);
PAINT PINK (-1800 3760);
FORCEPROP 2 LAST CDS_LIB mstr_standard
J 2
(-1800 3750);
DISPLAY 0.787234 (-1800 3750);
PAINT MONO (-1800 3750);
DISPLAY INVISIBLE (-1800 3750);
FORCEPROP 1 LAST BODY_TYPE PLUMBING
J 2
(-1800 3700);
DISPLAY 1.234043 (-1800 3700);
PAINT GREEN (-1800 3700);
DISPLAY INVISIBLE (-1800 3700);
FORCEPROP 1 LAST HDL_TAP TRUE
J 2
(-2125 3625);
DISPLAY 1.234043 (-2125 3625);
PAINT GREEN (-2125 3625);
DISPLAY INVISIBLE (-2125 3625);
FORCEPROP 1 LAST PATH I72
J 2
(-1800 3750);
DISPLAY 0.936170 (-1800 3750);
PAINT GREEN (-1800 3750);
DISPLAY INVISIBLE (-1800 3750);
FORCEADD TAP..6
R 2
(-1800 3350);
FORCEPROP 3 LASTPIN (-1850 3350) SIG_NAME M_J_DQ<35>
J 0
(-1840 3360);
DISPLAY 0.659574 (-1840 3360);
PAINT MONO (-1840 3360);
DISPLAY INVISIBLE (-1840 3360);
FORCEPROP 1 LASTPIN (-1850 3350) BN 35
J 2
(-1800 3360);
DISPLAY 0.617021 (-1800 3360);
PAINT PINK (-1800 3360);
FORCEPROP 2 LAST CDS_LIB mstr_standard
J 2
(-1800 3350);
DISPLAY 0.787234 (-1800 3350);
PAINT MONO (-1800 3350);
DISPLAY INVISIBLE (-1800 3350);
FORCEPROP 1 LAST BODY_TYPE PLUMBING
J 2
(-1800 3300);
DISPLAY 1.234043 (-1800 3300);
PAINT GREEN (-1800 3300);
DISPLAY INVISIBLE (-1800 3300);
FORCEPROP 1 LAST HDL_TAP TRUE
J 2
(-2125 3225);
DISPLAY 1.234043 (-2125 3225);
PAINT GREEN (-2125 3225);
DISPLAY INVISIBLE (-2125 3225);
FORCEPROP 1 LAST PATH I73
J 2
(-1800 3350);
DISPLAY 0.936170 (-1800 3350);
PAINT GREEN (-1800 3350);
DISPLAY INVISIBLE (-1800 3350);
FORCEADD TAP..6
R 2
(-1800 3400);
FORCEPROP 3 LASTPIN (-1850 3400) SIG_NAME M_J_DQ<34>
J 0
(-1840 3410);
DISPLAY 0.659574 (-1840 3410);
PAINT MONO (-1840 3410);
DISPLAY INVISIBLE (-1840 3410);
FORCEPROP 1 LASTPIN (-1850 3400) BN 34
J 2
(-1800 3410);
DISPLAY 0.617021 (-1800 3410);
PAINT PINK (-1800 3410);
FORCEPROP 2 LAST CDS_LIB mstr_standard
J 2
(-1800 3400);
DISPLAY 0.787234 (-1800 3400);
PAINT MONO (-1800 3400);
DISPLAY INVISIBLE (-1800 3400);
FORCEPROP 1 LAST BODY_TYPE PLUMBING
J 2
(-1800 3350);
DISPLAY 1.234043 (-1800 3350);
PAINT GREEN (-1800 3350);
DISPLAY INVISIBLE (-1800 3350);
FORCEPROP 1 LAST HDL_TAP TRUE
J 2
(-2125 3275);
DISPLAY 1.234043 (-2125 3275);
PAINT GREEN (-2125 3275);
DISPLAY INVISIBLE (-2125 3275);
FORCEPROP 1 LAST PATH I74
J 2
(-1800 3400);
DISPLAY 0.936170 (-1800 3400);
PAINT GREEN (-1800 3400);
DISPLAY INVISIBLE (-1800 3400);
FORCEADD TAP..6
R 2
(-1800 3300);
FORCEPROP 3 LASTPIN (-1850 3300) SIG_NAME M_J_DQ<32>
J 0
(-1840 3310);
DISPLAY 0.659574 (-1840 3310);
PAINT MONO (-1840 3310);
DISPLAY INVISIBLE (-1840 3310);
FORCEPROP 1 LASTPIN (-1850 3300) BN 32
J 2
(-1800 3310);
DISPLAY 0.617021 (-1800 3310);
PAINT PINK (-1800 3310);
FORCEPROP 2 LAST CDS_LIB mstr_standard
J 2
(-1800 3300);
DISPLAY 0.787234 (-1800 3300);
PAINT MONO (-1800 3300);
DISPLAY INVISIBLE (-1800 3300);
FORCEPROP 1 LAST BODY_TYPE PLUMBING
J 2
(-1800 3250);
DISPLAY 1.234043 (-1800 3250);
PAINT GREEN (-1800 3250);
DISPLAY INVISIBLE (-1800 3250);
FORCEPROP 1 LAST HDL_TAP TRUE
J 2
(-2125 3175);
DISPLAY 1.234043 (-2125 3175);
PAINT GREEN (-2125 3175);
DISPLAY INVISIBLE (-2125 3175);
FORCEPROP 1 LAST PATH I75
J 2
(-1800 3300);
DISPLAY 0.936170 (-1800 3300);
PAINT GREEN (-1800 3300);
DISPLAY INVISIBLE (-1800 3300);
FORCEADD TAP..6
R 2
(-1800 3450);
FORCEPROP 3 LASTPIN (-1850 3450) SIG_NAME M_J_DQ<37>
J 0
(-1840 3460);
DISPLAY 0.659574 (-1840 3460);
PAINT MONO (-1840 3460);
DISPLAY INVISIBLE (-1840 3460);
FORCEPROP 1 LASTPIN (-1850 3450) BN 37
J 2
(-1800 3460);
DISPLAY 0.617021 (-1800 3460);
PAINT PINK (-1800 3460);
FORCEPROP 2 LAST CDS_LIB mstr_standard
J 2
(-1800 3450);
DISPLAY 0.787234 (-1800 3450);
PAINT MONO (-1800 3450);
DISPLAY INVISIBLE (-1800 3450);
FORCEPROP 1 LAST BODY_TYPE PLUMBING
J 2
(-1800 3400);
DISPLAY 1.234043 (-1800 3400);
PAINT GREEN (-1800 3400);
DISPLAY INVISIBLE (-1800 3400);
FORCEPROP 1 LAST HDL_TAP TRUE
J 2
(-2125 3325);
DISPLAY 1.234043 (-2125 3325);
PAINT GREEN (-2125 3325);
DISPLAY INVISIBLE (-2125 3325);
FORCEPROP 1 LAST PATH I76
J 2
(-1800 3450);
DISPLAY 0.936170 (-1800 3450);
PAINT GREEN (-1800 3450);
DISPLAY INVISIBLE (-1800 3450);
FORCEADD TAP..6
R 2
(-1800 3500);
FORCEPROP 3 LASTPIN (-1850 3500) SIG_NAME M_J_DQ<36>
J 0
(-1840 3510);
DISPLAY 0.659574 (-1840 3510);
PAINT MONO (-1840 3510);
DISPLAY INVISIBLE (-1840 3510);
FORCEPROP 1 LASTPIN (-1850 3500) BN 36
J 2
(-1800 3510);
DISPLAY 0.617021 (-1800 3510);
PAINT PINK (-1800 3510);
FORCEPROP 2 LAST CDS_LIB mstr_standard
J 2
(-1800 3500);
DISPLAY 0.787234 (-1800 3500);
PAINT MONO (-1800 3500);
DISPLAY INVISIBLE (-1800 3500);
FORCEPROP 1 LAST BODY_TYPE PLUMBING
J 2
(-1800 3450);
DISPLAY 1.234043 (-1800 3450);
PAINT GREEN (-1800 3450);
DISPLAY INVISIBLE (-1800 3450);
FORCEPROP 1 LAST HDL_TAP TRUE
J 2
(-2125 3375);
DISPLAY 1.234043 (-2125 3375);
PAINT GREEN (-2125 3375);
DISPLAY INVISIBLE (-2125 3375);
FORCEPROP 1 LAST PATH I77
J 2
(-1800 3500);
DISPLAY 0.936170 (-1800 3500);
PAINT GREEN (-1800 3500);
DISPLAY INVISIBLE (-1800 3500);
FORCEADD TAP..6
R 2
(-1800 3150);
FORCEPROP 3 LASTPIN (-1850 3150) SIG_NAME M_J_DQ<31>
J 0
(-1840 3160);
DISPLAY 0.659574 (-1840 3160);
PAINT MONO (-1840 3160);
DISPLAY INVISIBLE (-1840 3160);
FORCEPROP 1 LASTPIN (-1850 3150) BN 31
J 2
(-1800 3160);
DISPLAY 0.617021 (-1800 3160);
PAINT PINK (-1800 3160);
FORCEPROP 2 LAST CDS_LIB mstr_standard
J 2
(-1800 3150);
DISPLAY 0.787234 (-1800 3150);
PAINT MONO (-1800 3150);
DISPLAY INVISIBLE (-1800 3150);
FORCEPROP 1 LAST BODY_TYPE PLUMBING
J 2
(-1800 3100);
DISPLAY 1.234043 (-1800 3100);
PAINT GREEN (-1800 3100);
DISPLAY INVISIBLE (-1800 3100);
FORCEPROP 1 LAST HDL_TAP TRUE
J 2
(-2125 3025);
DISPLAY 1.234043 (-2125 3025);
PAINT GREEN (-2125 3025);
DISPLAY INVISIBLE (-2125 3025);
FORCEPROP 1 LAST PATH I78
J 2
(-1800 3150);
DISPLAY 0.936170 (-1800 3150);
PAINT GREEN (-1800 3150);
DISPLAY INVISIBLE (-1800 3150);
FORCEADD TAP..6
R 2
(-1800 3100);
FORCEPROP 3 LASTPIN (-1850 3100) SIG_NAME M_J_DQ<28>
J 0
(-1840 3110);
DISPLAY 0.659574 (-1840 3110);
PAINT MONO (-1840 3110);
DISPLAY INVISIBLE (-1840 3110);
FORCEPROP 1 LASTPIN (-1850 3100) BN 28
J 2
(-1800 3110);
DISPLAY 0.617021 (-1800 3110);
PAINT PINK (-1800 3110);
FORCEPROP 2 LAST CDS_LIB mstr_standard
J 2
(-1800 3100);
DISPLAY 0.787234 (-1800 3100);
PAINT MONO (-1800 3100);
DISPLAY INVISIBLE (-1800 3100);
FORCEPROP 1 LAST BODY_TYPE PLUMBING
J 2
(-1800 3050);
DISPLAY 1.234043 (-1800 3050);
PAINT GREEN (-1800 3050);
DISPLAY INVISIBLE (-1800 3050);
FORCEPROP 1 LAST HDL_TAP TRUE
J 2
(-2125 2975);
DISPLAY 1.234043 (-2125 2975);
PAINT GREEN (-2125 2975);
DISPLAY INVISIBLE (-2125 2975);
FORCEPROP 1 LAST PATH I79
J 2
(-1800 3100);
DISPLAY 0.936170 (-1800 3100);
PAINT GREEN (-1800 3100);
DISPLAY INVISIBLE (-1800 3100);
FORCEADD TAP..6
R 2
(850 4900);
FORCEPROP 3 LASTPIN (800 4900) SIG_NAME M_J_DQS_DN<15>
J 0
(810 4910);
DISPLAY 0.659574 (810 4910);
PAINT MONO (810 4910);
DISPLAY INVISIBLE (810 4910);
FORCEPROP 1 LASTPIN (800 4900) BN 15
J 2
(850 4910);
DISPLAY 0.617021 (850 4910);
PAINT PINK (850 4910);
FORCEPROP 2 LAST CDS_LIB mstr_standard
J 0
(850 4900);
DISPLAY 0.787234 (850 4900);
PAINT MONO (850 4900);
DISPLAY INVISIBLE (850 4900);
FORCEPROP 1 LAST BODY_TYPE PLUMBING
J 2
(850 4850);
DISPLAY 1.234043 (850 4850);
PAINT GREEN (850 4850);
DISPLAY INVISIBLE (850 4850);
FORCEPROP 1 LAST HDL_TAP TRUE
J 2
(525 4775);
DISPLAY 1.234043 (525 4775);
PAINT GREEN (525 4775);
DISPLAY INVISIBLE (525 4775);
FORCEPROP 1 LAST PATH I8
J 2
(850 4900);
DISPLAY 0.936170 (850 4900);
PAINT GREEN (850 4900);
DISPLAY INVISIBLE (850 4900);
FORCEADD TAP..6
R 2
(-1800 3050);
FORCEPROP 3 LASTPIN (-1850 3050) SIG_NAME M_J_DQ<29>
J 0
(-1840 3060);
DISPLAY 0.659574 (-1840 3060);
PAINT MONO (-1840 3060);
DISPLAY INVISIBLE (-1840 3060);
FORCEPROP 1 LASTPIN (-1850 3050) BN 29
J 2
(-1800 3060);
DISPLAY 0.617021 (-1800 3060);
PAINT PINK (-1800 3060);
FORCEPROP 2 LAST CDS_LIB mstr_standard
J 2
(-1800 3050);
DISPLAY 0.787234 (-1800 3050);
PAINT MONO (-1800 3050);
DISPLAY INVISIBLE (-1800 3050);
FORCEPROP 1 LAST BODY_TYPE PLUMBING
J 2
(-1800 3000);
DISPLAY 1.234043 (-1800 3000);
PAINT GREEN (-1800 3000);
DISPLAY INVISIBLE (-1800 3000);
FORCEPROP 1 LAST HDL_TAP TRUE
J 2
(-2125 2925);
DISPLAY 1.234043 (-2125 2925);
PAINT GREEN (-2125 2925);
DISPLAY INVISIBLE (-2125 2925);
FORCEPROP 1 LAST PATH I80
J 2
(-1800 3050);
DISPLAY 0.936170 (-1800 3050);
PAINT GREEN (-1800 3050);
DISPLAY INVISIBLE (-1800 3050);
FORCEADD TAP..6
R 2
(-1800 3200);
FORCEPROP 3 LASTPIN (-1850 3200) SIG_NAME M_J_DQ<30>
J 0
(-1840 3210);
DISPLAY 0.659574 (-1840 3210);
PAINT MONO (-1840 3210);
DISPLAY INVISIBLE (-1840 3210);
FORCEPROP 1 LASTPIN (-1850 3200) BN 30
J 2
(-1800 3210);
DISPLAY 0.617021 (-1800 3210);
PAINT PINK (-1800 3210);
FORCEPROP 2 LAST CDS_LIB mstr_standard
J 2
(-1800 3200);
DISPLAY 0.787234 (-1800 3200);
PAINT MONO (-1800 3200);
DISPLAY INVISIBLE (-1800 3200);
FORCEPROP 1 LAST BODY_TYPE PLUMBING
J 2
(-1800 3150);
DISPLAY 1.234043 (-1800 3150);
PAINT GREEN (-1800 3150);
DISPLAY INVISIBLE (-1800 3150);
FORCEPROP 1 LAST HDL_TAP TRUE
J 2
(-2125 3075);
DISPLAY 1.234043 (-2125 3075);
PAINT GREEN (-2125 3075);
DISPLAY INVISIBLE (-2125 3075);
FORCEPROP 1 LAST PATH I81
J 2
(-1800 3200);
DISPLAY 0.936170 (-1800 3200);
PAINT GREEN (-1800 3200);
DISPLAY INVISIBLE (-1800 3200);
FORCEADD TAP..6
R 2
(-1800 3250);
FORCEPROP 3 LASTPIN (-1850 3250) SIG_NAME M_J_DQ<33>
J 0
(-1840 3260);
DISPLAY 0.659574 (-1840 3260);
PAINT MONO (-1840 3260);
DISPLAY INVISIBLE (-1840 3260);
FORCEPROP 1 LASTPIN (-1850 3250) BN 33
J 2
(-1800 3260);
DISPLAY 0.617021 (-1800 3260);
PAINT PINK (-1800 3260);
FORCEPROP 2 LAST CDS_LIB mstr_standard
J 2
(-1800 3250);
DISPLAY 0.787234 (-1800 3250);
PAINT MONO (-1800 3250);
DISPLAY INVISIBLE (-1800 3250);
FORCEPROP 1 LAST BODY_TYPE PLUMBING
J 2
(-1800 3200);
DISPLAY 1.234043 (-1800 3200);
PAINT GREEN (-1800 3200);
DISPLAY INVISIBLE (-1800 3200);
FORCEPROP 1 LAST HDL_TAP TRUE
J 2
(-2125 3125);
DISPLAY 1.234043 (-2125 3125);
PAINT GREEN (-2125 3125);
DISPLAY INVISIBLE (-2125 3125);
FORCEPROP 1 LAST PATH I82
J 2
(-1800 3250);
DISPLAY 0.936170 (-1800 3250);
PAINT GREEN (-1800 3250);
DISPLAY INVISIBLE (-1800 3250);
FORCEADD TAP..6
R 2
(-1800 2850);
FORCEPROP 3 LASTPIN (-1850 2850) SIG_NAME M_J_DQ<25>
J 0
(-1840 2860);
DISPLAY 0.659574 (-1840 2860);
PAINT MONO (-1840 2860);
DISPLAY INVISIBLE (-1840 2860);
FORCEPROP 1 LASTPIN (-1850 2850) BN 25
J 2
(-1800 2860);
DISPLAY 0.617021 (-1800 2860);
PAINT PINK (-1800 2860);
FORCEPROP 2 LAST CDS_LIB mstr_standard
J 2
(-1800 2850);
DISPLAY 0.787234 (-1800 2850);
PAINT MONO (-1800 2850);
DISPLAY INVISIBLE (-1800 2850);
FORCEPROP 1 LAST BODY_TYPE PLUMBING
J 2
(-1800 2800);
DISPLAY 1.234043 (-1800 2800);
PAINT GREEN (-1800 2800);
DISPLAY INVISIBLE (-1800 2800);
FORCEPROP 1 LAST HDL_TAP TRUE
J 2
(-2125 2725);
DISPLAY 1.234043 (-2125 2725);
PAINT GREEN (-2125 2725);
DISPLAY INVISIBLE (-2125 2725);
FORCEPROP 1 LAST PATH I83
J 2
(-1800 2850);
DISPLAY 0.936170 (-1800 2850);
PAINT GREEN (-1800 2850);
DISPLAY INVISIBLE (-1800 2850);
FORCEADD TAP..6
R 2
(-1800 2900);
FORCEPROP 3 LASTPIN (-1850 2900) SIG_NAME M_J_DQ<24>
J 0
(-1840 2910);
DISPLAY 0.659574 (-1840 2910);
PAINT MONO (-1840 2910);
DISPLAY INVISIBLE (-1840 2910);
FORCEPROP 1 LASTPIN (-1850 2900) BN 24
J 2
(-1800 2910);
DISPLAY 0.617021 (-1800 2910);
PAINT PINK (-1800 2910);
FORCEPROP 2 LAST CDS_LIB mstr_standard
J 2
(-1800 2900);
DISPLAY 0.787234 (-1800 2900);
PAINT MONO (-1800 2900);
DISPLAY INVISIBLE (-1800 2900);
FORCEPROP 1 LAST BODY_TYPE PLUMBING
J 2
(-1800 2850);
DISPLAY 1.234043 (-1800 2850);
PAINT GREEN (-1800 2850);
DISPLAY INVISIBLE (-1800 2850);
FORCEPROP 1 LAST HDL_TAP TRUE
J 2
(-2125 2775);
DISPLAY 1.234043 (-2125 2775);
PAINT GREEN (-2125 2775);
DISPLAY INVISIBLE (-2125 2775);
FORCEPROP 1 LAST PATH I84
J 2
(-1800 2900);
DISPLAY 0.936170 (-1800 2900);
PAINT GREEN (-1800 2900);
DISPLAY INVISIBLE (-1800 2900);
FORCEADD TAP..6
R 2
(-1800 2800);
FORCEPROP 3 LASTPIN (-1850 2800) SIG_NAME M_J_DQ<22>
J 0
(-1840 2810);
DISPLAY 0.659574 (-1840 2810);
PAINT MONO (-1840 2810);
DISPLAY INVISIBLE (-1840 2810);
FORCEPROP 1 LASTPIN (-1850 2800) BN 22
J 2
(-1800 2810);
DISPLAY 0.617021 (-1800 2810);
PAINT PINK (-1800 2810);
FORCEPROP 2 LAST CDS_LIB mstr_standard
J 2
(-1800 2800);
DISPLAY 0.787234 (-1800 2800);
PAINT MONO (-1800 2800);
DISPLAY INVISIBLE (-1800 2800);
FORCEPROP 1 LAST BODY_TYPE PLUMBING
J 2
(-1800 2750);
DISPLAY 1.234043 (-1800 2750);
PAINT GREEN (-1800 2750);
DISPLAY INVISIBLE (-1800 2750);
FORCEPROP 1 LAST HDL_TAP TRUE
J 2
(-2125 2675);
DISPLAY 1.234043 (-2125 2675);
PAINT GREEN (-2125 2675);
DISPLAY INVISIBLE (-2125 2675);
FORCEPROP 1 LAST PATH I85
J 2
(-1800 2800);
DISPLAY 0.936170 (-1800 2800);
PAINT GREEN (-1800 2800);
DISPLAY INVISIBLE (-1800 2800);
FORCEADD TAP..6
R 2
(-1800 2750);
FORCEPROP 3 LASTPIN (-1850 2750) SIG_NAME M_J_DQ<23>
J 0
(-1840 2760);
DISPLAY 0.659574 (-1840 2760);
PAINT MONO (-1840 2760);
DISPLAY INVISIBLE (-1840 2760);
FORCEPROP 1 LASTPIN (-1850 2750) BN 23
J 2
(-1800 2760);
DISPLAY 0.617021 (-1800 2760);
PAINT PINK (-1800 2760);
FORCEPROP 2 LAST CDS_LIB mstr_standard
J 2
(-1800 2750);
DISPLAY 0.787234 (-1800 2750);
PAINT MONO (-1800 2750);
DISPLAY INVISIBLE (-1800 2750);
FORCEPROP 1 LAST BODY_TYPE PLUMBING
J 2
(-1800 2700);
DISPLAY 1.234043 (-1800 2700);
PAINT GREEN (-1800 2700);
DISPLAY INVISIBLE (-1800 2700);
FORCEPROP 1 LAST HDL_TAP TRUE
J 2
(-2125 2625);
DISPLAY 1.234043 (-2125 2625);
PAINT GREEN (-2125 2625);
DISPLAY INVISIBLE (-2125 2625);
FORCEPROP 1 LAST PATH I86
J 2
(-1800 2750);
DISPLAY 0.936170 (-1800 2750);
PAINT GREEN (-1800 2750);
DISPLAY INVISIBLE (-1800 2750);
FORCEADD TAP..6
R 2
(-1800 2950);
FORCEPROP 3 LASTPIN (-1850 2950) SIG_NAME M_J_DQ<27>
J 0
(-1840 2960);
DISPLAY 0.659574 (-1840 2960);
PAINT MONO (-1840 2960);
DISPLAY INVISIBLE (-1840 2960);
FORCEPROP 1 LASTPIN (-1850 2950) BN 27
J 2
(-1800 2960);
DISPLAY 0.617021 (-1800 2960);
PAINT PINK (-1800 2960);
FORCEPROP 2 LAST CDS_LIB mstr_standard
J 2
(-1800 2950);
DISPLAY 0.787234 (-1800 2950);
PAINT MONO (-1800 2950);
DISPLAY INVISIBLE (-1800 2950);
FORCEPROP 1 LAST BODY_TYPE PLUMBING
J 2
(-1800 2900);
DISPLAY 1.234043 (-1800 2900);
PAINT GREEN (-1800 2900);
DISPLAY INVISIBLE (-1800 2900);
FORCEPROP 1 LAST HDL_TAP TRUE
J 2
(-2125 2825);
DISPLAY 1.234043 (-2125 2825);
PAINT GREEN (-2125 2825);
DISPLAY INVISIBLE (-2125 2825);
FORCEPROP 1 LAST PATH I87
J 2
(-1800 2950);
DISPLAY 0.936170 (-1800 2950);
PAINT GREEN (-1800 2950);
DISPLAY INVISIBLE (-1800 2950);
FORCEADD TAP..6
R 2
(-1800 3000);
FORCEPROP 3 LASTPIN (-1850 3000) SIG_NAME M_J_DQ<26>
J 0
(-1840 3010);
DISPLAY 0.659574 (-1840 3010);
PAINT MONO (-1840 3010);
DISPLAY INVISIBLE (-1840 3010);
FORCEPROP 1 LASTPIN (-1850 3000) BN 26
J 2
(-1800 3010);
DISPLAY 0.617021 (-1800 3010);
PAINT PINK (-1800 3010);
FORCEPROP 2 LAST CDS_LIB mstr_standard
J 2
(-1800 3000);
DISPLAY 0.787234 (-1800 3000);
PAINT MONO (-1800 3000);
DISPLAY INVISIBLE (-1800 3000);
FORCEPROP 1 LAST BODY_TYPE PLUMBING
J 2
(-1800 2950);
DISPLAY 1.234043 (-1800 2950);
PAINT GREEN (-1800 2950);
DISPLAY INVISIBLE (-1800 2950);
FORCEPROP 1 LAST HDL_TAP TRUE
J 2
(-2125 2875);
DISPLAY 1.234043 (-2125 2875);
PAINT GREEN (-2125 2875);
DISPLAY INVISIBLE (-2125 2875);
FORCEPROP 1 LAST PATH I88
J 2
(-1800 3000);
DISPLAY 0.936170 (-1800 3000);
PAINT GREEN (-1800 3000);
DISPLAY INVISIBLE (-1800 3000);
FORCEADD TAP..6
R 2
(-1800 2650);
FORCEPROP 3 LASTPIN (-1850 2650) SIG_NAME M_J_DQ<21>
J 0
(-1840 2660);
DISPLAY 0.659574 (-1840 2660);
PAINT MONO (-1840 2660);
DISPLAY INVISIBLE (-1840 2660);
FORCEPROP 1 LASTPIN (-1850 2650) BN 21
J 2
(-1800 2660);
DISPLAY 0.617021 (-1800 2660);
PAINT PINK (-1800 2660);
FORCEPROP 2 LAST CDS_LIB mstr_standard
J 2
(-1800 2650);
DISPLAY 0.787234 (-1800 2650);
PAINT MONO (-1800 2650);
DISPLAY INVISIBLE (-1800 2650);
FORCEPROP 1 LAST BODY_TYPE PLUMBING
J 2
(-1800 2600);
DISPLAY 1.234043 (-1800 2600);
PAINT GREEN (-1800 2600);
DISPLAY INVISIBLE (-1800 2600);
FORCEPROP 1 LAST HDL_TAP TRUE
J 2
(-2125 2525);
DISPLAY 1.234043 (-2125 2525);
PAINT GREEN (-2125 2525);
DISPLAY INVISIBLE (-2125 2525);
FORCEPROP 1 LAST PATH I89
J 2
(-1800 2650);
DISPLAY 0.936170 (-1800 2650);
PAINT GREEN (-1800 2650);
DISPLAY INVISIBLE (-1800 2650);
FORCEADD TAP..6
R 2
(850 4600);
FORCEPROP 3 LASTPIN (800 4600) SIG_NAME M_J_DQS_DN<12>
J 0
(810 4610);
DISPLAY 0.659574 (810 4610);
PAINT MONO (810 4610);
DISPLAY INVISIBLE (810 4610);
FORCEPROP 1 LASTPIN (800 4600) BN 12
J 2
(850 4610);
DISPLAY 0.617021 (850 4610);
PAINT PINK (850 4610);
FORCEPROP 2 LAST CDS_LIB mstr_standard
J 0
(850 4600);
DISPLAY 0.787234 (850 4600);
PAINT MONO (850 4600);
DISPLAY INVISIBLE (850 4600);
FORCEPROP 1 LAST BODY_TYPE PLUMBING
J 2
(850 4550);
DISPLAY 1.234043 (850 4550);
PAINT GREEN (850 4550);
DISPLAY INVISIBLE (850 4550);
FORCEPROP 1 LAST HDL_TAP TRUE
J 2
(525 4475);
DISPLAY 1.234043 (525 4475);
PAINT GREEN (525 4475);
DISPLAY INVISIBLE (525 4475);
FORCEPROP 1 LAST PATH I9
J 2
(850 4600);
DISPLAY 0.936170 (850 4600);
PAINT GREEN (850 4600);
DISPLAY INVISIBLE (850 4600);
FORCEADD TAP..6
R 2
(-1800 2600);
FORCEPROP 3 LASTPIN (-1850 2600) SIG_NAME M_J_DQ<18>
J 0
(-1840 2610);
DISPLAY 0.659574 (-1840 2610);
PAINT MONO (-1840 2610);
DISPLAY INVISIBLE (-1840 2610);
FORCEPROP 1 LASTPIN (-1850 2600) BN 18
J 2
(-1800 2610);
DISPLAY 0.617021 (-1800 2610);
PAINT PINK (-1800 2610);
FORCEPROP 2 LAST CDS_LIB mstr_standard
J 2
(-1800 2600);
DISPLAY 0.787234 (-1800 2600);
PAINT MONO (-1800 2600);
DISPLAY INVISIBLE (-1800 2600);
FORCEPROP 1 LAST BODY_TYPE PLUMBING
J 2
(-1800 2550);
DISPLAY 1.234043 (-1800 2550);
PAINT GREEN (-1800 2550);
DISPLAY INVISIBLE (-1800 2550);
FORCEPROP 1 LAST HDL_TAP TRUE
J 2
(-2125 2475);
DISPLAY 1.234043 (-2125 2475);
PAINT GREEN (-2125 2475);
DISPLAY INVISIBLE (-2125 2475);
FORCEPROP 1 LAST PATH I90
J 2
(-1800 2600);
DISPLAY 0.936170 (-1800 2600);
PAINT GREEN (-1800 2600);
DISPLAY INVISIBLE (-1800 2600);
FORCEADD TAP..6
R 2
(-1800 2550);
FORCEPROP 3 LASTPIN (-1850 2550) SIG_NAME M_J_DQ<19>
J 0
(-1840 2560);
DISPLAY 0.659574 (-1840 2560);
PAINT MONO (-1840 2560);
DISPLAY INVISIBLE (-1840 2560);
FORCEPROP 1 LASTPIN (-1850 2550) BN 19
J 2
(-1800 2560);
DISPLAY 0.617021 (-1800 2560);
PAINT PINK (-1800 2560);
FORCEPROP 2 LAST CDS_LIB mstr_standard
J 2
(-1800 2550);
DISPLAY 0.787234 (-1800 2550);
PAINT MONO (-1800 2550);
DISPLAY INVISIBLE (-1800 2550);
FORCEPROP 1 LAST BODY_TYPE PLUMBING
J 2
(-1800 2500);
DISPLAY 1.234043 (-1800 2500);
PAINT GREEN (-1800 2500);
DISPLAY INVISIBLE (-1800 2500);
FORCEPROP 1 LAST HDL_TAP TRUE
J 2
(-2125 2425);
DISPLAY 1.234043 (-2125 2425);
PAINT GREEN (-2125 2425);
DISPLAY INVISIBLE (-2125 2425);
FORCEPROP 1 LAST PATH I91
J 2
(-1800 2550);
DISPLAY 0.936170 (-1800 2550);
PAINT GREEN (-1800 2550);
DISPLAY INVISIBLE (-1800 2550);
FORCEADD TAP..6
R 2
(-1800 2500);
FORCEPROP 3 LASTPIN (-1850 2500) SIG_NAME M_J_DQ<16>
J 0
(-1840 2510);
DISPLAY 0.659574 (-1840 2510);
PAINT MONO (-1840 2510);
DISPLAY INVISIBLE (-1840 2510);
FORCEPROP 1 LASTPIN (-1850 2500) BN 16
J 2
(-1800 2510);
DISPLAY 0.617021 (-1800 2510);
PAINT PINK (-1800 2510);
FORCEPROP 2 LAST CDS_LIB mstr_standard
J 2
(-1800 2500);
DISPLAY 0.787234 (-1800 2500);
PAINT MONO (-1800 2500);
DISPLAY INVISIBLE (-1800 2500);
FORCEPROP 1 LAST BODY_TYPE PLUMBING
J 2
(-1800 2450);
DISPLAY 1.234043 (-1800 2450);
PAINT GREEN (-1800 2450);
DISPLAY INVISIBLE (-1800 2450);
FORCEPROP 1 LAST HDL_TAP TRUE
J 2
(-2125 2375);
DISPLAY 1.234043 (-2125 2375);
PAINT GREEN (-2125 2375);
DISPLAY INVISIBLE (-2125 2375);
FORCEPROP 1 LAST PATH I92
J 2
(-1800 2500);
DISPLAY 0.936170 (-1800 2500);
PAINT GREEN (-1800 2500);
DISPLAY INVISIBLE (-1800 2500);
FORCEADD TAP..6
R 2
(-1800 2700);
FORCEPROP 3 LASTPIN (-1850 2700) SIG_NAME M_J_DQ<20>
J 0
(-1840 2710);
DISPLAY 0.659574 (-1840 2710);
PAINT MONO (-1840 2710);
DISPLAY INVISIBLE (-1840 2710);
FORCEPROP 1 LASTPIN (-1850 2700) BN 20
J 2
(-1800 2710);
DISPLAY 0.617021 (-1800 2710);
PAINT PINK (-1800 2710);
FORCEPROP 2 LAST CDS_LIB mstr_standard
J 2
(-1800 2700);
DISPLAY 0.787234 (-1800 2700);
PAINT MONO (-1800 2700);
DISPLAY INVISIBLE (-1800 2700);
FORCEPROP 1 LAST BODY_TYPE PLUMBING
J 2
(-1800 2650);
DISPLAY 1.234043 (-1800 2650);
PAINT GREEN (-1800 2650);
DISPLAY INVISIBLE (-1800 2650);
FORCEPROP 1 LAST HDL_TAP TRUE
J 2
(-2125 2575);
DISPLAY 1.234043 (-2125 2575);
PAINT GREEN (-2125 2575);
DISPLAY INVISIBLE (-2125 2575);
FORCEPROP 1 LAST PATH I93
J 2
(-1800 2700);
DISPLAY 0.936170 (-1800 2700);
PAINT GREEN (-1800 2700);
DISPLAY INVISIBLE (-1800 2700);
FORCEADD TAP..6
R 2
(-1800 2400);
FORCEPROP 3 LASTPIN (-1850 2400) SIG_NAME M_J_DQ<14>
J 0
(-1840 2410);
DISPLAY 0.659574 (-1840 2410);
PAINT MONO (-1840 2410);
DISPLAY INVISIBLE (-1840 2410);
FORCEPROP 1 LASTPIN (-1850 2400) BN 14
J 2
(-1800 2410);
DISPLAY 0.617021 (-1800 2410);
PAINT PINK (-1800 2410);
FORCEPROP 2 LAST CDS_LIB mstr_standard
J 2
(-1800 2400);
DISPLAY 0.787234 (-1800 2400);
PAINT MONO (-1800 2400);
DISPLAY INVISIBLE (-1800 2400);
FORCEPROP 1 LAST BODY_TYPE PLUMBING
J 2
(-1800 2350);
DISPLAY 1.234043 (-1800 2350);
PAINT GREEN (-1800 2350);
DISPLAY INVISIBLE (-1800 2350);
FORCEPROP 1 LAST HDL_TAP TRUE
J 2
(-2125 2275);
DISPLAY 1.234043 (-2125 2275);
PAINT GREEN (-2125 2275);
DISPLAY INVISIBLE (-2125 2275);
FORCEPROP 1 LAST PATH I94
J 2
(-1800 2400);
DISPLAY 0.936170 (-1800 2400);
PAINT GREEN (-1800 2400);
DISPLAY INVISIBLE (-1800 2400);
FORCEADD TAP..6
R 2
(-1800 2350);
FORCEPROP 3 LASTPIN (-1850 2350) SIG_NAME M_J_DQ<15>
J 0
(-1840 2360);
DISPLAY 0.659574 (-1840 2360);
PAINT MONO (-1840 2360);
DISPLAY INVISIBLE (-1840 2360);
FORCEPROP 1 LASTPIN (-1850 2350) BN 15
J 2
(-1800 2360);
DISPLAY 0.617021 (-1800 2360);
PAINT PINK (-1800 2360);
FORCEPROP 2 LAST CDS_LIB mstr_standard
J 2
(-1800 2350);
DISPLAY 0.787234 (-1800 2350);
PAINT MONO (-1800 2350);
DISPLAY INVISIBLE (-1800 2350);
FORCEPROP 1 LAST BODY_TYPE PLUMBING
J 2
(-1800 2300);
DISPLAY 1.234043 (-1800 2300);
PAINT GREEN (-1800 2300);
DISPLAY INVISIBLE (-1800 2300);
FORCEPROP 1 LAST HDL_TAP TRUE
J 2
(-2125 2225);
DISPLAY 1.234043 (-2125 2225);
PAINT GREEN (-2125 2225);
DISPLAY INVISIBLE (-2125 2225);
FORCEPROP 1 LAST PATH I95
J 2
(-1800 2350);
DISPLAY 0.936170 (-1800 2350);
PAINT GREEN (-1800 2350);
DISPLAY INVISIBLE (-1800 2350);
FORCEADD TAP..6
R 2
(-1800 2250);
FORCEPROP 3 LASTPIN (-1850 2250) SIG_NAME M_J_DQ<13>
J 0
(-1840 2260);
DISPLAY 0.659574 (-1840 2260);
PAINT MONO (-1840 2260);
DISPLAY INVISIBLE (-1840 2260);
FORCEPROP 1 LASTPIN (-1850 2250) BN 13
J 2
(-1800 2260);
DISPLAY 0.617021 (-1800 2260);
PAINT PINK (-1800 2260);
FORCEPROP 2 LAST CDS_LIB mstr_standard
J 2
(-1800 2250);
DISPLAY 0.787234 (-1800 2250);
PAINT MONO (-1800 2250);
DISPLAY INVISIBLE (-1800 2250);
FORCEPROP 1 LAST BODY_TYPE PLUMBING
J 2
(-1800 2200);
DISPLAY 1.234043 (-1800 2200);
PAINT GREEN (-1800 2200);
DISPLAY INVISIBLE (-1800 2200);
FORCEPROP 1 LAST HDL_TAP TRUE
J 2
(-2125 2125);
DISPLAY 1.234043 (-2125 2125);
PAINT GREEN (-2125 2125);
DISPLAY INVISIBLE (-2125 2125);
FORCEPROP 1 LAST PATH I96
J 2
(-1800 2250);
DISPLAY 0.936170 (-1800 2250);
PAINT GREEN (-1800 2250);
DISPLAY INVISIBLE (-1800 2250);
FORCEADD TAP..6
R 2
(-1800 2300);
FORCEPROP 3 LASTPIN (-1850 2300) SIG_NAME M_J_DQ<12>
J 0
(-1840 2310);
DISPLAY 0.659574 (-1840 2310);
PAINT MONO (-1840 2310);
DISPLAY INVISIBLE (-1840 2310);
FORCEPROP 1 LASTPIN (-1850 2300) BN 12
J 2
(-1800 2310);
DISPLAY 0.617021 (-1800 2310);
PAINT PINK (-1800 2310);
FORCEPROP 2 LAST CDS_LIB mstr_standard
J 2
(-1800 2300);
DISPLAY 0.787234 (-1800 2300);
PAINT MONO (-1800 2300);
DISPLAY INVISIBLE (-1800 2300);
FORCEPROP 1 LAST BODY_TYPE PLUMBING
J 2
(-1800 2250);
DISPLAY 1.234043 (-1800 2250);
PAINT GREEN (-1800 2250);
DISPLAY INVISIBLE (-1800 2250);
FORCEPROP 1 LAST HDL_TAP TRUE
J 2
(-2125 2175);
DISPLAY 1.234043 (-2125 2175);
PAINT GREEN (-2125 2175);
DISPLAY INVISIBLE (-2125 2175);
FORCEPROP 1 LAST PATH I97
J 2
(-1800 2300);
DISPLAY 0.936170 (-1800 2300);
PAINT GREEN (-1800 2300);
DISPLAY INVISIBLE (-1800 2300);
FORCEADD TAP..6
R 2
(-1800 2450);
FORCEPROP 3 LASTPIN (-1850 2450) SIG_NAME M_J_DQ<17>
J 0
(-1840 2460);
DISPLAY 0.659574 (-1840 2460);
PAINT MONO (-1840 2460);
DISPLAY INVISIBLE (-1840 2460);
FORCEPROP 1 LASTPIN (-1850 2450) BN 17
J 2
(-1800 2460);
DISPLAY 0.617021 (-1800 2460);
PAINT PINK (-1800 2460);
FORCEPROP 2 LAST CDS_LIB mstr_standard
J 2
(-1800 2450);
DISPLAY 0.787234 (-1800 2450);
PAINT MONO (-1800 2450);
DISPLAY INVISIBLE (-1800 2450);
FORCEPROP 1 LAST BODY_TYPE PLUMBING
J 2
(-1800 2400);
DISPLAY 1.234043 (-1800 2400);
PAINT GREEN (-1800 2400);
DISPLAY INVISIBLE (-1800 2400);
FORCEPROP 1 LAST HDL_TAP TRUE
J 2
(-2125 2325);
DISPLAY 1.234043 (-2125 2325);
PAINT GREEN (-2125 2325);
DISPLAY INVISIBLE (-2125 2325);
FORCEPROP 1 LAST PATH I98
J 2
(-1800 2450);
DISPLAY 0.936170 (-1800 2450);
PAINT GREEN (-1800 2450);
DISPLAY INVISIBLE (-1800 2450);
FORCEADD TAP..6
R 2
(-1800 2200);
FORCEPROP 3 LASTPIN (-1850 2200) SIG_NAME M_J_DQ<10>
J 0
(-1840 2210);
DISPLAY 0.659574 (-1840 2210);
PAINT MONO (-1840 2210);
DISPLAY INVISIBLE (-1840 2210);
FORCEPROP 1 LASTPIN (-1850 2200) BN 10
J 2
(-1800 2210);
DISPLAY 0.617021 (-1800 2210);
PAINT PINK (-1800 2210);
FORCEPROP 2 LAST CDS_LIB mstr_standard
J 2
(-1800 2200);
DISPLAY 0.787234 (-1800 2200);
PAINT MONO (-1800 2200);
DISPLAY INVISIBLE (-1800 2200);
FORCEPROP 1 LAST BODY_TYPE PLUMBING
J 2
(-1800 2150);
DISPLAY 1.234043 (-1800 2150);
PAINT GREEN (-1800 2150);
DISPLAY INVISIBLE (-1800 2150);
FORCEPROP 1 LAST HDL_TAP TRUE
J 2
(-2125 2075);
DISPLAY 1.234043 (-2125 2075);
PAINT GREEN (-2125 2075);
DISPLAY INVISIBLE (-2125 2075);
FORCEPROP 1 LAST PATH I99
J 2
(-1800 2200);
DISPLAY 0.936170 (-1800 2200);
PAINT GREEN (-1800 2200);
DISPLAY INVISIBLE (-1800 2200);
FORCEADD BOM_NOTE..1
(-5050 5275);
FORCEPROP 0 LAST L1 STUFF FOR SKU A & B
J 0
(-5200 5175);
DISPLAY 1.063830 (-5200 5175);
PAINT WHITE (-5200 5175);
FORCEPROP 2 LAST CDS_LIB mstr_symbols
J 0
(-5050 5275);
PAINT ORANGE (-5050 5275);
DISPLAY INVISIBLE (-5050 5275);
FORCEPROP 2 LAST BOM_COST SB
J 0
(-5200 5250);
DISPLAY 1.361702 (-5200 5250);
PAINT ORANGE (-5200 5250);
DISPLAY INVISIBLE (-5200 5250);
FORCEPROP 1 LAST COMMENT_BODY TRUE
J 0
(-5025 5375);
DISPLAY 1.319149 (-5025 5375);
PAINT ORANGE (-5025 5375);
DISPLAY INVISIBLE (-5025 5375);
FORCEPROP 2 LAST ROOM SB_HEADERS
J 0
(-5200 5250);
DISPLAY 1.361702 (-5200 5250);
PAINT ORANGE (-5200 5250);
DISPLAY INVISIBLE (-5200 5250);
FORCEADD INTEL_CORP_BPAGE..1
(2650 500);
FORCEPROP 1 LAST CDS_CON_LAST_MODIFIED Fri Jun 16 17:48:30 2017
J 0
(1225 825);
DISPLAY 0.787234 (1225 825);
PAINT ORANGE (1225 825);
DISPLAY INVISIBLE (1225 825);
FORCEPROP 1 LAST CUSTOM_TXT_CDS <CURRENT_DESIGN_SHEET> OF <TOTAL_DESIGN_SHEETS>
J 0
(2150 525);
PAINT ORANGE (2150 525);
FORCEPROP 1 LAST CUSTOM_TXT_CDS <CON_LAST_MODIFIED>
J 0
(-1350 600);
PAINT ORANGE (-1350 600);
FORCEPROP 2 LAST CUSTOM_TXT_CDS <XR_PAGE_TITLE>
J 0
(-5240 5750);
DISPLAY 0.638298 (-5240 5750);
PAINT PINK (-5240 5750);
DISPLAY INVISIBLE (-5240 5750);
FORCEPROP 1 LAST SCH_TITLE CPU1 DDR4 CH J DIMM0
J 0
(-5275 550);
DISPLAY 1.212766 (-5275 550);
PAINT WHITE (-5275 550);
FORCEPROP 2 LAST CDS_LIB mstr_symbols
J 0
(2650 500);
DISPLAY 0.787234 (2650 500);
PAINT MONO (2650 500);
DISPLAY INVISIBLE (2650 500);
FORCEPROP 2 LAST PAGE_BORDER TRUE
J 0
(-5240 5750);
DISPLAY 0.680851 (-5240 5750);
PAINT PINK (-5240 5750);
DISPLAY INVISIBLE (-5240 5750);
FORCEPROP 1 LAST COMMENT_BODY TRUE
J 0
(2660 510);
DISPLAY 0.382979 (2660 510);
PAINT GREEN (2660 510);
DISPLAY INVISIBLE (2660 510);
FORCEPROP 2 LAST CDS_XR_PAGE_TITLE CR-81 : @BASEBOARD_FAB2_LIB.BASEBOARD_FAB2(SCH_1):PAGE81
J 0
(-5240 5750);
DISPLAY 0.638298 (-5240 5750);
PAINT PINK (-5240 5750);
DISPLAY INVISIBLE (-5240 5750);
WIRE 16 -1 (-1475 2475)(-1475 2400);
WIRE 16 -1 (-1475 2400)(-1050 2400);
WIRE 16 -1 (-1050 2350)(-1050 2400);
WIRE 16 -1 (-1050 2400)(-850 2400);
WIRE 16 -1 (-1050 2300)(-1050 2350);
WIRE 16 -1 (-1050 2350)(-850 2350);
WIRE 16 -1 (-1050 2250)(-1050 2300);
WIRE 16 -1 (-1050 2300)(-850 2300);
WIRE 16 -1 (-1050 2200)(-1050 2250);
WIRE 16 -1 (-1050 2250)(-850 2250);
WIRE 16 -1 (-1050 2150)(-1050 2200);
WIRE 16 -1 (-1050 2200)(-850 2200);
WIRE 16 -1 (-1050 2100)(-1050 2150);
WIRE 16 -1 (-1050 2150)(-850 2150);
WIRE 16 -1 (-1050 2050)(-1050 2100);
WIRE 16 -1 (-1050 2100)(-850 2100);
WIRE 16 -1 (-1050 2000)(-1050 2050);
WIRE 16 -1 (-1050 2050)(-850 2050);
WIRE 16 -1 (-1050 1950)(-1050 2000);
WIRE 16 -1 (-1050 2000)(-850 2000);
WIRE 16 -1 (-1050 1900)(-1050 1950);
WIRE 16 -1 (-1050 1950)(-850 1950);
WIRE 16 -1 (-1050 1850)(-1050 1900);
WIRE 16 -1 (-1050 1900)(-850 1900);
WIRE 16 -1 (-1050 1800)(-1050 1850);
WIRE 16 -1 (-1050 1850)(-850 1850);
WIRE 16 -1 (-1050 1750)(-1050 1800);
WIRE 16 -1 (-1050 1800)(-850 1800);
WIRE 16 -1 (-1050 1700)(-1050 1750);
WIRE 16 -1 (-1050 1750)(-850 1750);
WIRE 16 -1 (-1050 1650)(-1050 1700);
WIRE 16 -1 (-1050 1700)(-850 1700);
WIRE 16 -1 (-1050 1600)(-1050 1650);
WIRE 16 -1 (-1050 1650)(-850 1650);
WIRE 16 -1 (-1050 1550)(-1050 1600);
WIRE 16 -1 (-1050 1600)(-850 1600);
WIRE 16 -1 (-1050 1500)(-1050 1550);
WIRE 16 -1 (-1050 1550)(-850 1550);
WIRE 16 -1 (-1050 1450)(-1050 1500);
WIRE 16 -1 (-1050 1500)(-850 1500);
WIRE 16 -1 (-1050 1400)(-1050 1450);
WIRE 16 -1 (-1050 1450)(-850 1450);
WIRE 16 -1 (-1050 1350)(-1050 1400);
WIRE 16 -1 (-1050 1400)(-850 1400);
WIRE 16 -1 (-1050 1300)(-1050 1350);
WIRE 16 -1 (-1050 1350)(-850 1350);
WIRE 16 -1 (-1050 1250)(-1050 1300);
WIRE 16 -1 (-1050 1300)(-850 1300);
WIRE 16 -1 (-1050 1200)(-1050 1250);
WIRE 16 -1 (-1050 1250)(-850 1250);
WIRE 16 -1 (-1050 1150)(-1050 1200);
WIRE 16 -1 (-1050 1200)(-850 1200);
WIRE 16 -1 (-1050 1150)(-850 1150);
WIRE 16 -1 (2450 1150)(2450 1250);
WIRE 16 -1 (2450 1250)(2450 1300);
WIRE 16 -1 (2450 1250)(2250 1250);
WIRE 16 -1 (2450 1300)(2450 1350);
WIRE 16 -1 (2450 1300)(2250 1300);
WIRE 16 -1 (2450 1350)(2450 1400);
WIRE 16 -1 (2450 1350)(2250 1350);
WIRE 16 -1 (2450 1400)(2450 1450);
WIRE 16 -1 (2450 1400)(2250 1400);
WIRE 16 -1 (2450 1450)(2450 1500);
WIRE 16 -1 (2250 1450)(2450 1450);
WIRE 16 -1 (2450 1500)(2450 1550);
WIRE 16 -1 (2250 1500)(2450 1500);
WIRE 16 -1 (2450 1550)(2450 1600);
WIRE 16 -1 (2450 1550)(2250 1550);
WIRE 16 -1 (2450 1600)(2450 1650);
WIRE 16 -1 (2450 1600)(2250 1600);
WIRE 16 -1 (2450 1650)(2450 1700);
WIRE 16 -1 (2450 1650)(2250 1650);
WIRE 16 -1 (2450 1700)(2450 1750);
WIRE 16 -1 (2450 1700)(2250 1700);
WIRE 16 -1 (2450 1750)(2450 1800);
WIRE 16 -1 (2450 1750)(2250 1750);
WIRE 16 -1 (2450 1800)(2450 1850);
WIRE 16 -1 (2450 1800)(2250 1800);
WIRE 16 -1 (2450 1850)(2450 1900);
WIRE 16 -1 (2450 1850)(2250 1850);
WIRE 16 -1 (2450 1900)(2450 1950);
WIRE 16 -1 (2450 1900)(2250 1900);
WIRE 16 -1 (2450 1950)(2450 2000);
WIRE 16 -1 (2450 1950)(2250 1950);
WIRE 16 -1 (2450 2000)(2450 2050);
WIRE 16 -1 (2450 2000)(2250 2000);
WIRE 16 -1 (2450 2050)(2450 2100);
WIRE 16 -1 (2450 2050)(2250 2050);
WIRE 16 -1 (2450 2100)(2450 2150);
WIRE 16 -1 (2450 2100)(2250 2100);
WIRE 16 -1 (2450 2150)(2450 2200);
WIRE 16 -1 (2450 2150)(2250 2150);
WIRE 16 -1 (2450 2200)(2450 2250);
WIRE 16 -1 (2450 2200)(2250 2200);
WIRE 16 -1 (2450 2250)(2450 2300);
WIRE 16 -1 (2450 2250)(2250 2250);
WIRE 16 -1 (2450 2300)(2450 2350);
WIRE 16 -1 (2450 2300)(2250 2300);
WIRE 16 -1 (2450 2350)(2450 2400);
WIRE 16 -1 (2450 2350)(2250 2350);
WIRE 16 -1 (2450 2400)(2450 2450);
WIRE 16 -1 (2450 2400)(2250 2400);
WIRE 16 -1 (2450 2450)(2450 2500);
WIRE 16 -1 (2450 2450)(2250 2450);
WIRE 16 -1 (2450 2500)(2450 2550);
WIRE 16 -1 (2250 2500)(2450 2500);
WIRE 16 -1 (2450 2550)(2450 2600);
WIRE 16 -1 (2450 2550)(2250 2550);
WIRE 16 -1 (2450 2600)(2450 2650);
WIRE 16 -1 (2250 2600)(2450 2600);
WIRE 16 -1 (2450 2650)(2450 2700);
WIRE 16 -1 (2250 2650)(2450 2650);
WIRE 16 -1 (2450 2700)(2450 2750);
WIRE 16 -1 (2250 2700)(2450 2700);
WIRE 16 -1 (2450 2750)(2450 2800);
WIRE 16 -1 (2250 2750)(2450 2750);
WIRE 16 -1 (2450 2800)(2450 2850);
WIRE 16 -1 (2250 2800)(2450 2800);
WIRE 16 -1 (2450 2850)(2450 2900);
WIRE 16 -1 (2250 2850)(2450 2850);
WIRE 16 -1 (2450 2900)(2450 2950);
WIRE 16 -1 (2250 2900)(2450 2900);
WIRE 16 -1 (2450 2950)(2450 3000);
WIRE 16 -1 (2250 2950)(2450 2950);
WIRE 16 -1 (2450 3000)(2450 3050);
WIRE 16 -1 (2250 3000)(2450 3000);
WIRE 16 -1 (2450 3050)(2450 3100);
WIRE 16 -1 (2250 3050)(2450 3050);
WIRE 16 -1 (2450 3100)(2450 3150);
WIRE 16 -1 (2250 3100)(2450 3100);
WIRE 16 -1 (2450 3150)(2450 3200);
WIRE 16 -1 (2250 3150)(2450 3150);
WIRE 16 -1 (2450 3200)(2450 3250);
WIRE 16 -1 (2250 3200)(2450 3200);
WIRE 16 -1 (2450 3250)(2450 3300);
WIRE 16 -1 (2250 3250)(2450 3250);
WIRE 16 -1 (2450 3300)(2450 3350);
WIRE 16 -1 (2250 3300)(2450 3300);
WIRE 16 -1 (2450 3350)(2450 3400);
WIRE 16 -1 (2250 3350)(2450 3350);
WIRE 16 -1 (2450 3400)(2450 3450);
WIRE 16 -1 (2250 3400)(2450 3400);
WIRE 16 -1 (2450 3450)(2450 3500);
WIRE 16 -1 (2250 3450)(2450 3450);
WIRE 16 -1 (2450 3500)(2450 3550);
WIRE 16 -1 (2250 3500)(2450 3500);
WIRE 16 -1 (2250 3550)(2450 3550);
WIRE 16 -1 (-5200 1900)(-5200 1800);
WIRE 16 -1 (-3300 1900)(-5200 1900);
WIRE 16 -1 (-3300 1900)(-3300 1850);
WIRE 16 -1 (-3050 1900)(-3300 1900);
WIRE 16 -1 (-3300 1850)(-3050 1850);
WIRE 16 -1 (-4550 1350)(-4550 1250);
WIRE 16 -1 (-1050 2950)(-1050 2850);
WIRE 16 -1 (-1050 2850)(-1050 2800);
WIRE 16 -1 (-1050 2850)(-850 2850);
WIRE 16 -1 (-1050 2800)(-1050 2750);
WIRE 16 -1 (-1050 2800)(-850 2800);
WIRE 16 -1 (-1050 2750)(-1050 2700);
WIRE 16 -1 (-1050 2750)(-850 2750);
WIRE 16 -1 (-1050 2700)(-1050 2650);
WIRE 16 -1 (-1050 2700)(-850 2700);
WIRE 16 -1 (-1050 2650)(-850 2650);
WIRE 16 -1 (-1200 2650)(-1200 2550);
WIRE 16 -1 (-1200 2550)(-1050 2550);
WIRE 16 -1 (-1050 2500)(-1050 2550);
WIRE 16 -1 (-1050 2550)(-850 2550);
WIRE 16 -1 (-1050 2500)(-850 2500);
WIRE 16 -1 (-5200 2100)(-5200 2000);
WIRE 16 -1 (-3300 2000)(-5200 2000);
WIRE 16 -1 (-3300 1950)(-3300 2000);
WIRE 16 -1 (-3050 2000)(-3300 2000);
WIRE 16 -1 (-3300 1950)(-3050 1950);
WIRE 16 -1 (350 2850)(350 2925);
WIRE 16 -1 (350 2800)(350 2850);
WIRE 16 -1 (150 2850)(350 2850);
WIRE 16 -1 (150 2800)(350 2800);
WIRE 16 -1 (1050 1150)(1050 1250);
WIRE 16 -1 (1050 1250)(1050 1300);
WIRE 16 -1 (1250 1250)(1050 1250);
WIRE 16 -1 (1050 1300)(1050 1350);
WIRE 16 -1 (1250 1300)(1050 1300);
WIRE 16 -1 (1050 1350)(1050 1400);
WIRE 16 -1 (1250 1350)(1050 1350);
WIRE 16 -1 (1050 1400)(1050 1450);
WIRE 16 -1 (1250 1400)(1050 1400);
WIRE 16 -1 (1050 1450)(1050 1500);
WIRE 16 -1 (1250 1450)(1050 1450);
WIRE 16 -1 (1050 1500)(1050 1550);
WIRE 16 -1 (1050 1500)(1250 1500);
WIRE 16 -1 (1050 1550)(1050 1600);
WIRE 16 -1 (1250 1550)(1050 1550);
WIRE 16 -1 (1050 1600)(1050 1650);
WIRE 16 -1 (1250 1600)(1050 1600);
WIRE 16 -1 (1050 1650)(1050 1700);
WIRE 16 -1 (1250 1650)(1050 1650);
WIRE 16 -1 (1050 1700)(1050 1750);
WIRE 16 -1 (1250 1700)(1050 1700);
WIRE 16 -1 (1050 1750)(1050 1800);
WIRE 16 -1 (1050 1750)(1250 1750);
WIRE 16 -1 (1050 1800)(1050 1850);
WIRE 16 -1 (1250 1800)(1050 1800);
WIRE 16 -1 (1050 1850)(1050 1900);
WIRE 16 -1 (1250 1850)(1050 1850);
WIRE 16 -1 (1050 1900)(1050 1950);
WIRE 16 -1 (1250 1900)(1050 1900);
WIRE 16 -1 (1050 1950)(1050 2000);
WIRE 16 -1 (1250 1950)(1050 1950);
WIRE 16 -1 (1050 2000)(1050 2050);
WIRE 16 -1 (1050 2000)(1250 2000);
WIRE 16 -1 (1050 2050)(1050 2100);
WIRE 16 -1 (1250 2050)(1050 2050);
WIRE 16 -1 (1050 2100)(1050 2150);
WIRE 16 -1 (1250 2100)(1050 2100);
WIRE 16 -1 (1050 2150)(1050 2200);
WIRE 16 -1 (1250 2150)(1050 2150);
WIRE 16 -1 (1050 2200)(1050 2250);
WIRE 16 -1 (1250 2200)(1050 2200);
WIRE 16 -1 (1050 2250)(1050 2300);
WIRE 16 -1 (1050 2250)(1250 2250);
WIRE 16 -1 (1050 2300)(1050 2350);
WIRE 16 -1 (1250 2300)(1050 2300);
WIRE 16 -1 (1050 2350)(1050 2400);
WIRE 16 -1 (1250 2350)(1050 2350);
WIRE 16 -1 (1050 2400)(1050 2450);
WIRE 16 -1 (1250 2400)(1050 2400);
WIRE 16 -1 (1050 2450)(1050 2500);
WIRE 16 -1 (1250 2450)(1050 2450);
WIRE 16 -1 (1050 2500)(1050 2550);
WIRE 16 -1 (1050 2500)(1250 2500);
WIRE 16 -1 (1050 2550)(1050 2600);
WIRE 16 -1 (1250 2550)(1050 2550);
WIRE 16 -1 (1050 2600)(1050 2650);
WIRE 16 -1 (1250 2600)(1050 2600);
WIRE 16 -1 (1050 2650)(1050 2700);
WIRE 16 -1 (1250 2650)(1050 2650);
WIRE 16 -1 (1050 2700)(1050 2750);
WIRE 16 -1 (1250 2700)(1050 2700);
WIRE 16 -1 (1050 2750)(1050 2800);
WIRE 16 -1 (1250 2750)(1050 2750);
WIRE 16 -1 (1050 2800)(1050 2850);
WIRE 16 -1 (1050 2800)(1250 2800);
WIRE 16 -1 (1050 2850)(1050 2900);
WIRE 16 -1 (1250 2850)(1050 2850);
WIRE 16 -1 (1050 2900)(1050 2950);
WIRE 16 -1 (1250 2900)(1050 2900);
WIRE 16 -1 (1050 2950)(1050 3000);
WIRE 16 -1 (1250 2950)(1050 2950);
WIRE 16 -1 (1050 3000)(1050 3050);
WIRE 16 -1 (1250 3000)(1050 3000);
WIRE 16 -1 (1050 3050)(1050 3100);
WIRE 16 -1 (1250 3050)(1050 3050);
WIRE 16 -1 (1050 3100)(1050 3150);
WIRE 16 -1 (1050 3100)(1250 3100);
WIRE 16 -1 (1050 3150)(1050 3200);
WIRE 16 -1 (1250 3150)(1050 3150);
WIRE 16 -1 (1050 3200)(1050 3250);
WIRE 16 -1 (1250 3200)(1050 3200);
WIRE 16 -1 (1050 3250)(1050 3300);
WIRE 16 -1 (1250 3250)(1050 3250);
WIRE 16 -1 (1050 3300)(1050 3350);
WIRE 16 -1 (1250 3300)(1050 3300);
WIRE 16 -1 (1050 3350)(1050 3400);
WIRE 16 -1 (1250 3350)(1050 3350);
WIRE 16 -1 (1050 3400)(1050 3450);
WIRE 16 -1 (1050 3400)(1250 3400);
WIRE 16 -1 (1050 3450)(1050 3500);
WIRE 16 -1 (1250 3450)(1050 3450);
WIRE 16 -1 (1050 3500)(1050 3550);
WIRE 16 -1 (1250 3500)(1050 3500);
WIRE 16 -1 (1250 3550)(1050 3550);
WIRE 17 -1 (700 3475)(700 3575);
WIRE 17 -1 (700 3575)(700 3675);
WIRE 17 -1 (700 3675)(700 3775);
WIRE 17 -1 (700 3775)(700 3875);
WIRE 17 -1 (700 3875)(700 3975);
WIRE 17 -1 (700 3975)(700 4075);
WIRE 17 -1 (700 4075)(700 4175);
WIRE 17 -1 (700 4175)(700 4275);
WIRE 17 -1 (700 4275)(700 4375);
WIRE 17 -1 (700 4375)(700 4475);
WIRE 17 -1 (700 4475)(700 4575);
WIRE 17 -1 (700 4575)(700 4675);
WIRE 17 -1 (700 4675)(700 4775);
WIRE 17 -1 (700 4775)(700 4875);
WIRE 17 -1 (700 4875)(700 4975);
WIRE 17 -1 (1500 5200)(700 5200);
FORCEPROP 2 LAST SIG_NAME M_J_DQS_DP<17:0>
J 0
(950 5210);
DISPLAY 0.617021 (950 5210);
PAINT ORANGE (950 5210);
WIRE 17 -1 (700 5175)(700 5200);
WIRE 17 -1 (700 4975)(700 5075);
WIRE 17 -1 (700 5075)(700 5175);
WIRE 17 -1 (1500 5150)(900 5150);
FORCEPROP 2 LAST SIG_NAME M_J_DQS_DN<17:0>
J 0
(950 5160);
DISPLAY 0.617021 (950 5160);
PAINT ORANGE (950 5160);
WIRE 17 -1 (900 3425)(900 3525);
WIRE 17 -1 (900 3525)(900 3625);
WIRE 17 -1 (900 5125)(900 5150);
WIRE 17 -1 (900 5025)(900 5125);
WIRE 17 -1 (900 3625)(900 3725);
WIRE 17 -1 (900 3725)(900 3825);
WIRE 17 -1 (900 4925)(900 5025);
WIRE 17 -1 (900 4825)(900 4925);
WIRE 17 -1 (900 3825)(900 3925);
WIRE 17 -1 (900 3925)(900 4025);
WIRE 17 -1 (900 4725)(900 4825);
WIRE 17 -1 (900 4625)(900 4725);
WIRE 17 -1 (900 4025)(900 4125);
WIRE 17 -1 (900 4125)(900 4225);
WIRE 17 -1 (900 4525)(900 4625);
WIRE 17 -1 (900 4425)(900 4525);
WIRE 17 -1 (900 4225)(900 4325);
WIRE 17 -1 (900 4325)(900 4425);
WIRE 17 -1 (-1750 1675)(-1750 1725);
WIRE 17 -1 (-1750 1725)(-1750 1775);
WIRE 17 -1 (-1750 1775)(-1750 1825);
WIRE 17 -1 (-1750 1825)(-1750 1875);
WIRE 17 -1 (-1750 1875)(-1750 1925);
WIRE 17 -1 (-1750 1925)(-1750 1975);
WIRE 17 -1 (-1750 1975)(-1750 2025);
WIRE 17 -1 (-1750 2025)(-1750 2075);
WIRE 17 -1 (-1750 2075)(-1750 2125);
WIRE 17 -1 (-1750 2125)(-1750 2175);
WIRE 17 -1 (-1750 2175)(-1750 2225);
WIRE 17 -1 (-1750 2225)(-1750 2275);
WIRE 17 -1 (-1750 2275)(-1750 2325);
WIRE 17 -1 (-1750 2325)(-1750 2375);
WIRE 17 -1 (-1750 2375)(-1750 2425);
WIRE 17 -1 (-1750 2425)(-1750 2475);
WIRE 17 -1 (-1750 2475)(-1750 2525);
WIRE 17 -1 (-1750 2525)(-1750 2575);
WIRE 17 -1 (-1750 2575)(-1750 2625);
WIRE 17 -1 (-1750 2625)(-1750 2675);
WIRE 17 -1 (-1750 2675)(-1750 2725);
WIRE 17 -1 (-1750 2725)(-1750 2775);
WIRE 17 -1 (-1750 2775)(-1750 2825);
WIRE 17 -1 (-1750 2825)(-1750 2875);
WIRE 17 -1 (-1750 2875)(-1750 2925);
WIRE 17 -1 (-1750 2925)(-1750 2975);
WIRE 17 -1 (-1750 2975)(-1750 3025);
WIRE 17 -1 (-1750 3025)(-1750 3075);
WIRE 17 -1 (-1750 3075)(-1750 3125);
WIRE 17 -1 (-1750 3125)(-1750 3175);
WIRE 17 -1 (-1750 3175)(-1750 3225);
WIRE 17 -1 (-1750 3225)(-1750 3275);
WIRE 17 -1 (-1750 3275)(-1750 3325);
WIRE 17 -1 (-1750 3325)(-1750 3375);
WIRE 17 -1 (-1750 3375)(-1750 3425);
WIRE 17 -1 (-1750 3425)(-1750 3475);
WIRE 17 -1 (-1750 3475)(-1750 3525);
WIRE 17 -1 (-1750 3525)(-1750 3575);
WIRE 17 -1 (-1750 3575)(-1750 3625);
WIRE 17 -1 (-1750 3625)(-1750 3675);
WIRE 17 -1 (-1750 3675)(-1750 3725);
WIRE 17 -1 (-1750 3725)(-1750 3775);
WIRE 17 -1 (-1750 3775)(-1750 3825);
WIRE 17 -1 (-1750 3825)(-1750 3875);
WIRE 17 -1 (-1750 3875)(-1750 3925);
WIRE 17 -1 (-1750 3925)(-1750 3975);
WIRE 17 -1 (-1750 3975)(-1750 4025);
WIRE 17 -1 (-1750 4025)(-1750 4075);
WIRE 17 -1 (-1750 4075)(-1750 4125);
WIRE 17 -1 (-1750 4125)(-1750 4175);
WIRE 17 -1 (-1750 4175)(-1750 4225);
WIRE 17 -1 (-1750 4225)(-1750 4275);
WIRE 17 -1 (-1750 4275)(-1750 4325);
WIRE 17 -1 (-1750 4325)(-1750 4375);
WIRE 17 -1 (-1350 4850)(-1750 4850);
FORCEPROP 2 LAST SIG_NAME M_J_DQ<63:0>
J 0
(-1710 4860);
DISPLAY 0.617021 (-1710 4860);
PAINT ORANGE (-1710 4860);
WIRE 17 -1 (-1750 4375)(-1750 4425);
WIRE 17 -1 (-1750 4425)(-1750 4475);
WIRE 17 -1 (-1750 4825)(-1750 4850);
WIRE 17 -1 (-1750 4775)(-1750 4825);
WIRE 17 -1 (-1750 4475)(-1750 4525);
WIRE 17 -1 (-1750 4525)(-1750 4575);
WIRE 17 -1 (-1750 4725)(-1750 4775);
WIRE 17 -1 (-1750 4675)(-1750 4725);
WIRE 17 -1 (-1750 4575)(-1750 4625);
WIRE 17 -1 (-1750 4625)(-1750 4675);
WIRE 17 -1 (-3350 3975)(-3350 4025);
WIRE 17 -1 (-3350 4025)(-3350 4075);
WIRE 17 -1 (-3350 4075)(-3350 4125);
WIRE 17 -1 (-3350 4125)(-3350 4175);
WIRE 17 -1 (-3900 4850)(-3350 4850);
FORCEPROP 2 LAST SIG_NAME M_J_MA<17:0>
J 0
(-3875 4860);
DISPLAY 0.617021 (-3875 4860);
PAINT ORANGE (-3875 4860);
WIRE 17 -1 (-3350 4175)(-3350 4225);
WIRE 17 -1 (-3350 4225)(-3350 4275);
WIRE 17 -1 (-3350 4825)(-3350 4850);
WIRE 17 -1 (-3350 4775)(-3350 4825);
WIRE 17 -1 (-3350 4275)(-3350 4325);
WIRE 17 -1 (-3350 4325)(-3350 4375);
WIRE 17 -1 (-3350 4725)(-3350 4775);
WIRE 17 -1 (-3350 4675)(-3350 4725);
WIRE 17 -1 (-3350 4375)(-3350 4425);
WIRE 17 -1 (-3350 4425)(-3350 4475);
WIRE 17 -1 (-3350 4625)(-3350 4675);
WIRE 17 -1 (-3350 4575)(-3350 4625);
WIRE 17 -1 (-3350 4475)(-3350 4525);
WIRE 17 -1 (-3350 4525)(-3350 4575);
WIRE 17 -1 (-3650 3650)(-4250 3650);
FORCEPROP 2 LAST SIG_NAME M_J_CLK_DP<3:0>
J 0
(-4225 3660);
DISPLAY 0.617021 (-4225 3660);
PAINT ORANGE (-4225 3660);
WIRE 17 -1 (-3650 3525)(-3650 3625);
WIRE 17 -1 (-3650 3625)(-3650 3650);
WIRE 17 -1 (-3800 3600)(-4250 3600);
FORCEPROP 2 LAST SIG_NAME M_J_CLK_DN<3:0>
J 0
(-4225 3610);
DISPLAY 0.617021 (-4225 3610);
PAINT ORANGE (-4225 3610);
WIRE 17 -1 (-3800 3575)(-3800 3475);
WIRE 17 -1 (-3800 3575)(-3800 3600);
WIRE 17 -1 (-3350 3175)(-3350 3225);
WIRE 17 -1 (-3350 3225)(-3350 3275);
WIRE 17 -1 (-3350 3350)(-3900 3350);
WIRE 17 -1 (-3350 3275)(-3350 3325);
WIRE 17 -1 (-3350 3325)(-3350 3350);
FORCEPROP 2 LAST SIG_NAME M_J_CS_N<7:0>
J 0
(-3875 3360);
DISPLAY 0.617021 (-3875 3360);
PAINT ORANGE (-3875 3360);
WIRE 17 -1 (-3350 3800)(-3900 3800);
FORCEPROP 2 LAST SIG_NAME M_J_BG<1:0>
J 0
(-3875 3810);
DISPLAY 0.617021 (-3875 3810);
PAINT ORANGE (-3875 3810);
WIRE 17 -1 (-3350 3725)(-3350 3775);
WIRE 17 -1 (-3350 3775)(-3350 3800);
WIRE 17 -1 (-3350 3900)(-3900 3900);
FORCEPROP 2 LAST SIG_NAME M_J_BA<1:0>
J 0
(-3875 3910);
DISPLAY 0.617021 (-3875 3910);
PAINT ORANGE (-3875 3910);
WIRE 17 -1 (-3350 3900)(-3350 3875);
WIRE 17 -1 (-3350 3825)(-3350 3875);
WIRE 17 -1 (-3350 2425)(-3350 2475);
WIRE 17 -1 (-3350 2475)(-3350 2525);
WIRE 17 -1 (-3350 2800)(-3900 2800);
FORCEPROP 2 LAST SIG_NAME M_J_ECC<7:0>
J 0
(-3875 2810);
DISPLAY 0.617021 (-3875 2810);
PAINT ORANGE (-3875 2810);
WIRE 17 -1 (-3350 2525)(-3350 2575);
WIRE 17 -1 (-3350 2575)(-3350 2625);
WIRE 17 -1 (-3350 2775)(-3350 2800);
WIRE 17 -1 (-3350 2725)(-3350 2775);
WIRE 17 -1 (-3350 2625)(-3350 2675);
WIRE 17 -1 (-3350 2675)(-3350 2725);
WIRE 17 -1 (-3350 3100)(-3900 3100);
FORCEPROP 2 LAST SIG_NAME M_J_CKE<3:0>
J 0
(-3875 3110);
DISPLAY 0.617021 (-3875 3110);
PAINT ORANGE (-3875 3110);
WIRE 17 -1 (-3350 3025)(-3350 3075);
WIRE 17 -1 (-3350 3075)(-3350 3100);
WIRE 17 -1 (-3350 2950)(-3900 2950);
FORCEPROP 2 LAST SIG_NAME M_J_ODT<3:0>
J 0
(-3875 2960);
DISPLAY 0.617021 (-3875 2960);
PAINT ORANGE (-3875 2960);
WIRE 17 -1 (-3350 2925)(-3350 2950);
WIRE 17 -1 (-3350 2875)(-3350 2925);
WIRE 16 -1 (600 3750)(400 3750);
WIRE 16 -1 (-4650 1650)(-4550 1650);
WIRE 16 -1 (-4550 1650)(-4550 1550);
WIRE 16 -1 (-3050 1650)(-4550 1650);
FORCEPROP 2 LAST SIG_NAME M_J_VREF
J 0
(-3850 1660);
DISPLAY 0.617021 (-3850 1660);
PAINT ORANGE (-3850 1660);
WIRE 16 -1 (800 4300)(400 4300);
WIRE 16 -1 (600 4250)(400 4250);
WIRE 16 -1 (800 4200)(400 4200);
WIRE 16 -1 (-1850 2900)(-2050 2900);
WIRE 16 -1 (-3050 2100)(-4050 2100);
FORCEPROP 2 LAST SIG_NAME M_J_ACT_N
J 0
(-4000 2110);
DISPLAY 0.617021 (-4000 2110);
PAINT ORANGE (-4000 2110);
WIRE 16 -1 (-3500 2450)(-4275 2450);
FORCEPROP 2 LAST SIG_NAME FM_DIMM_EVENT_COD_N
J 0
(-4231 2467);
DISPLAY 0.617021 (-4231 2467);
PAINT ORANGE (-4231 2467);
WIRE 16 -1 (-3500 2200)(-3500 2450);
WIRE 16 -1 (-3500 2200)(-3050 2200);
WIRE 16 -1 (-3900 1500)(-3050 1500);
FORCEPROP 2 LAST SIG_NAME TP_CH_J_DIMM_J0_RFU_1
J 0
(-3850 1510);
DISPLAY 0.617021 (-3850 1510);
PAINT ORANGE (-3850 1510);
FORCEPROP 2 LASTPROP $XRERR UNIQUE?
J 0
(-4140 1500);
DISPLAY 0.638298 (-4140 1500);
PAINT MONO (-4140 1500);
DISPLAY INVISIBLE (-4140 1500);
WIRE 16 -1 (-3900 1450)(-3050 1450);
FORCEPROP 2 LAST SIG_NAME TP_CH_J_DIMM_J0_RFU_0
J 0
(-3850 1460);
DISPLAY 0.617021 (-3850 1460);
PAINT ORANGE (-3850 1460);
FORCEPROP 2 LASTPROP $XRERR UNIQUE?
J 0
(-4140 1450);
DISPLAY 0.638298 (-4140 1450);
PAINT MONO (-4140 1450);
DISPLAY INVISIBLE (-4140 1450);
WIRE 16 -1 (-3900 1550)(-3050 1550);
FORCEPROP 2 LAST SIG_NAME TP_CH_J_DIMM_J0_RFU_2
J 0
(-3850 1560);
DISPLAY 0.617021 (-3850 1560);
PAINT ORANGE (-3850 1560);
FORCEPROP 2 LASTPROP $XRERR UNIQUE?
J 0
(-4140 1550);
DISPLAY 0.638298 (-4140 1550);
PAINT MONO (-4140 1550);
DISPLAY INVISIBLE (-4140 1550);
WIRE 16 -1 (-3900 1750)(-3050 1750);
FORCEPROP 2 LAST SIG_NAME SMB_DDR_GHJ_VPP_SCL
J 0
(-3860 1760);
DISPLAY 0.617021 (-3860 1760);
PAINT ORANGE (-3860 1760);
WIRE 16 -1 (-3900 1800)(-3050 1800);
WIRE 16 -1 (-3900 1350)(-3050 1350);
FORCEPROP 2 LAST SIG_NAME FM_ADR_COMPLETE_GHJ_N
J 0
(-3850 1360);
DISPLAY 0.617021 (-3850 1360);
PAINT ORANGE (-3850 1360);
WIRE 16 -1 (-3450 2700)(-3900 2700);
FORCEPROP 2 LAST SIG_NAME M_GHJ_RST_N
J 0
(-3875 2710);
DISPLAY 0.617021 (-3875 2710);
PAINT ORANGE (-3875 2710);
WIRE 16 -1 (-3450 2250)(-3450 2700);
WIRE 16 -1 (-3050 2250)(-3450 2250);
WIRE 16 -1 (-3400 2750)(-3900 2750);
FORCEPROP 2 LAST SIG_NAME M_J_PAR
J 0
(-3875 2760);
DISPLAY 0.617021 (-3875 2760);
PAINT ORANGE (-3875 2760);
WIRE 16 -1 (-3400 2300)(-3400 2750);
WIRE 16 -1 (-3050 2300)(-3400 2300);
WIRE 16 -1 (-3150 3400)(-3900 3400);
FORCEPROP 2 LAST SIG_NAME M_J_C<2>
J 0
(-3875 3410);
DISPLAY 0.617021 (-3875 3410);
PAINT ORANGE (-3875 3410);
WIRE 16 -1 (-3150 3400)(-3150 3350);
WIRE 16 -1 (-3150 3350)(-3050 3350);
WIRE 16 -1 (-3050 3150)(-3250 3150);
WIRE 16 -1 (-3050 3000)(-3250 3000);
WIRE 16 -1 (-3050 2900)(-3250 2900);
WIRE 16 -1 (-3050 2850)(-3250 2850);
WIRE 16 -1 (-3050 2750)(-3250 2750);
WIRE 16 -1 (-3050 4050)(-3250 4050);
WIRE 16 -1 (-3050 3700)(-3250 3700);
WIRE 16 -1 (-3050 3050)(-3250 3050);
WIRE 16 -1 (-3050 2400)(-3250 2400);
WIRE 16 -1 (-3050 2450)(-3250 2450);
WIRE 16 -1 (-3050 2500)(-3250 2500);
WIRE 16 -1 (-3050 2550)(-3250 2550);
WIRE 16 -1 (-3050 2600)(-3250 2600);
WIRE 16 -1 (-3050 2650)(-3250 2650);
WIRE 16 -1 (-3050 2700)(-3250 2700);
WIRE 16 -1 (-3050 4000)(-3250 4000);
WIRE 16 -1 (-3050 3950)(-3250 3950);
WIRE 16 -1 (-3050 3200)(-3250 3200);
WIRE 16 -1 (-3050 3850)(-3250 3850);
WIRE 16 -1 (-3050 3800)(-3250 3800);
WIRE 16 -1 (-3050 3750)(-3250 3750);
WIRE 16 -1 (-3050 3250)(-3250 3250);
WIRE 16 -1 (-3050 3300)(-3250 3300);
WIRE 16 -1 (-3050 3450)(-3700 3450);
WIRE 16 -1 (-3050 3500)(-3550 3500);
WIRE 16 -1 (-3050 3550)(-3700 3550);
WIRE 16 -1 (-3050 3600)(-3550 3600);
WIRE 16 -1 (-3050 2150)(-4075 2150);
FORCEPROP 2 LAST SIG_NAME M_J_ALERT_N
J 0
(-4025 2160);
DISPLAY 0.617021 (-4025 2160);
PAINT ORANGE (-4025 2160);
WIRE 16 -1 (-1850 1900)(-2050 1900);
WIRE 16 -1 (-1850 1850)(-2050 1850);
WIRE 16 -1 (-1850 1800)(-2050 1800);
WIRE 16 -1 (-1850 1750)(-2050 1750);
WIRE 16 -1 (-1850 4000)(-2050 4000);
WIRE 16 -1 (-1850 4050)(-2050 4050);
WIRE 16 -1 (-1850 2400)(-2050 2400);
WIRE 16 -1 (-1850 2950)(-2050 2950);
WIRE 16 -1 (-1850 3000)(-2050 3000);
WIRE 16 -1 (-1850 3550)(-2050 3550);
WIRE 16 -1 (-1850 3450)(-2050 3450);
WIRE 16 -1 (-1850 3400)(-2050 3400);
WIRE 16 -1 (-1850 1650)(-2050 1650);
WIRE 16 -1 (-1850 1700)(-2050 1700);
WIRE 16 -1 (-1850 1950)(-2050 1950);
WIRE 16 -1 (-1850 2000)(-2050 2000);
WIRE 16 -1 (-1850 2050)(-2050 2050);
WIRE 16 -1 (-1850 2100)(-2050 2100);
WIRE 16 -1 (-1850 2200)(-2050 2200);
WIRE 16 -1 (-1850 2250)(-2050 2250);
WIRE 16 -1 (-1850 2300)(-2050 2300);
WIRE 16 -1 (-1850 2350)(-2050 2350);
WIRE 16 -1 (-1850 2450)(-2050 2450);
WIRE 16 -1 (-1850 2550)(-2050 2550);
WIRE 16 -1 (-1850 2600)(-2050 2600);
WIRE 16 -1 (-1850 2650)(-2050 2650);
WIRE 16 -1 (-1850 2700)(-2050 2700);
WIRE 16 -1 (-1850 2750)(-2050 2750);
WIRE 16 -1 (-1850 2800)(-2050 2800);
WIRE 16 -1 (-1850 2850)(-2050 2850);
WIRE 16 -1 (-1850 3150)(-2050 3150);
WIRE 16 -1 (-1850 3200)(-2050 3200);
WIRE 16 -1 (-1850 3250)(-2050 3250);
WIRE 16 -1 (-1850 3300)(-2050 3300);
WIRE 16 -1 (-1850 3350)(-2050 3350);
WIRE 16 -1 (-1850 3500)(-2050 3500);
WIRE 16 -1 (-1850 3600)(-2050 3600);
WIRE 16 -1 (-1850 3650)(-2050 3650);
WIRE 16 -1 (-1850 3700)(-2050 3700);
WIRE 16 -1 (-1850 3750)(-2050 3750);
WIRE 16 -1 (-1850 3800)(-2050 3800);
WIRE 16 -1 (-1850 3850)(-2050 3850);
WIRE 16 -1 (-1850 3900)(-2050 3900);
WIRE 16 -1 (-1850 3950)(-2050 3950);
WIRE 16 -1 (-1850 3050)(-2050 3050);
WIRE 16 -1 (-1850 3100)(-2050 3100);
WIRE 16 -1 (-1850 2150)(-2050 2150);
WIRE 16 -1 (-1850 2500)(-2050 2500);
WIRE 16 -1 (-3050 4750)(-3250 4750);
WIRE 16 -1 (-3050 4700)(-3250 4700);
WIRE 16 -1 (-3050 4650)(-3250 4650);
WIRE 16 -1 (-3050 4500)(-3250 4500);
WIRE 16 -1 (-3050 4450)(-3250 4450);
WIRE 16 -1 (-3050 4400)(-3250 4400);
WIRE 16 -1 (-3050 4350)(-3250 4350);
WIRE 16 -1 (-3050 4300)(-3250 4300);
WIRE 16 -1 (-3050 4250)(-3250 4250);
WIRE 16 -1 (-3050 4200)(-3250 4200);
WIRE 16 -1 (-3050 4150)(-3250 4150);
WIRE 16 -1 (-3050 4100)(-3250 4100);
WIRE 16 -1 (-3050 4800)(-3250 4800);
WIRE 16 -1 (-3050 4600)(-3250 4600);
WIRE 16 -1 (-3050 4550)(-3250 4550);
WIRE 16 -1 (-1850 4800)(-2050 4800);
WIRE 16 -1 (-1850 4750)(-2050 4750);
WIRE 16 -1 (-1850 4700)(-2050 4700);
WIRE 16 -1 (-1850 4100)(-2050 4100);
WIRE 16 -1 (-1850 4150)(-2050 4150);
WIRE 16 -1 (-1850 4200)(-2050 4200);
WIRE 16 -1 (-1850 4250)(-2050 4250);
WIRE 16 -1 (-1850 4300)(-2050 4300);
WIRE 16 -1 (-1850 4350)(-2050 4350);
WIRE 16 -1 (-1850 4550)(-2050 4550);
WIRE 16 -1 (-1850 4500)(-2050 4500);
WIRE 16 -1 (-1850 4400)(-2050 4400);
WIRE 16 -1 (-1850 4450)(-2050 4450);
WIRE 16 -1 (-1850 4600)(-2050 4600);
WIRE 16 -1 (-1850 4650)(-2050 4650);
WIRE 16 -1 (600 4050)(400 4050);
WIRE 16 -1 (800 4000)(400 4000);
WIRE 16 -1 (600 3950)(400 3950);
WIRE 16 -1 (800 3900)(400 3900);
WIRE 16 -1 (600 3850)(400 3850);
WIRE 16 -1 (800 3800)(400 3800);
WIRE 16 -1 (800 3700)(400 3700);
WIRE 16 -1 (600 3650)(400 3650);
WIRE 16 -1 (800 3600)(400 3600);
WIRE 16 -1 (600 3550)(400 3550);
WIRE 16 -1 (800 3500)(400 3500);
WIRE 16 -1 (600 3450)(400 3450);
WIRE 16 -1 (800 3400)(400 3400);
WIRE 16 -1 (600 4350)(400 4350);
WIRE 16 -1 (600 4150)(400 4150);
WIRE 16 -1 (800 4100)(400 4100);
WIRE 16 -1 (800 5100)(400 5100);
WIRE 16 -1 (600 5050)(400 5050);
WIRE 16 -1 (800 5000)(400 5000);
WIRE 16 -1 (600 4950)(400 4950);
WIRE 16 -1 (800 4900)(400 4900);
WIRE 16 -1 (600 4850)(400 4850);
WIRE 16 -1 (800 4800)(400 4800);
WIRE 16 -1 (600 4750)(400 4750);
WIRE 16 -1 (800 4700)(400 4700);
WIRE 16 -1 (600 4650)(400 4650);
WIRE 16 -1 (800 4600)(400 4600);
WIRE 16 -1 (600 4550)(400 4550);
WIRE 16 -1 (800 4500)(400 4500);
WIRE 16 -1 (600 4450)(400 4450);
WIRE 16 -1 (800 4400)(400 4400);
WIRE 16 -1 (600 5150)(400 5150);
DOT 1 (2450 3250);
DOT 1 (-1050 1200);
DOT 1 (2450 1950);
DOT 1 (1050 1350);
DOT 1 (1050 1450);
DOT 1 (2450 1450);
DOT 1 (2450 2900);
DOT 1 (2450 1800);
DOT 1 (2450 1850);
DOT 1 (350 2850);
DOT 1 (-3300 2000);
DOT 1 (1050 1250);
DOT 1 (1050 1300);
DOT 1 (1050 1400);
DOT 1 (1050 1550);
DOT 1 (1050 1500);
DOT 1 (1050 1600);
DOT 1 (1050 1700);
DOT 1 (1050 1650);
DOT 1 (1050 1750);
DOT 1 (1050 1800);
DOT 1 (1050 1850);
DOT 1 (1050 1950);
DOT 1 (1050 2000);
DOT 1 (1050 2050);
DOT 1 (1050 2100);
DOT 1 (1050 2150);
DOT 1 (1050 2200);
DOT 1 (1050 2250);
DOT 1 (1050 2350);
DOT 1 (1050 2300);
DOT 1 (1050 2400);
DOT 1 (1050 2450);
DOT 1 (1050 2500);
DOT 1 (1050 2600);
DOT 1 (1050 2550);
DOT 1 (1050 2650);
DOT 1 (1050 2700);
DOT 1 (1050 2750);
DOT 1 (1050 2850);
DOT 1 (1050 2800);
DOT 1 (1050 2900);
DOT 1 (1050 2950);
DOT 1 (1050 3000);
DOT 1 (1050 3150);
DOT 1 (1050 3100);
DOT 1 (1050 3050);
DOT 1 (1050 3250);
DOT 1 (1050 3200);
DOT 1 (1050 3300);
DOT 1 (1050 3350);
DOT 1 (1050 3400);
DOT 1 (1050 3450);
DOT 1 (1050 3500);
DOT 1 (2450 1250);
DOT 1 (2450 1300);
DOT 1 (2450 1350);
DOT 1 (2450 1400);
DOT 1 (2450 1500);
DOT 1 (2450 1550);
DOT 1 (2450 1600);
DOT 1 (2450 1650);
DOT 1 (2450 1700);
DOT 1 (2450 1750);
DOT 1 (2450 1900);
DOT 1 (2450 2000);
DOT 1 (2450 2050);
DOT 1 (2450 2100);
DOT 1 (2450 2150);
DOT 1 (2450 2200);
DOT 1 (2450 2250);
DOT 1 (2450 2300);
DOT 1 (2450 2350);
DOT 1 (2450 2400);
DOT 1 (2450 2450);
DOT 1 (2450 2500);
DOT 1 (2450 2550);
DOT 1 (2450 2600);
DOT 1 (2450 2650);
DOT 1 (2450 2700);
DOT 1 (2450 2750);
DOT 1 (2450 2800);
DOT 1 (2450 2850);
DOT 1 (2450 2950);
DOT 1 (2450 3000);
DOT 1 (2450 3050);
DOT 1 (2450 3100);
DOT 1 (2450 3150);
DOT 1 (2450 3200);
DOT 1 (2450 3300);
DOT 1 (2450 3350);
DOT 1 (2450 3400);
DOT 1 (2450 3450);
DOT 1 (2450 3500);
DOT 1 (-4550 1650);
DOT 1 (-1050 2700);
DOT 1 (-1050 2850);
DOT 1 (-1050 2800);
DOT 1 (-1050 2750);
DOT 1 (-1050 2550);
DOT 1 (-1050 2350);
DOT 1 (-1050 2200);
DOT 1 (-1050 2150);
DOT 1 (-1050 2100);
DOT 1 (-1050 2000);
DOT 1 (-1050 2050);
DOT 1 (-1050 1950);
DOT 1 (-1050 1900);
DOT 1 (-1050 1850);
DOT 1 (-1050 1750);
DOT 1 (-1050 1800);
DOT 1 (-1050 1700);
DOT 1 (-1050 1600);
DOT 1 (-1050 1650);
DOT 1 (-1050 1500);
DOT 1 (-1050 1550);
DOT 1 (-1050 1450);
DOT 1 (-1050 1400);
DOT 1 (-1050 1350);
DOT 1 (-1050 1300);
DOT 1 (-1050 1250);
DOT 1 (1050 1900);
DOT 1 (-3300 1900);
DOT 1 (-1050 2300);
DOT 1 (-1050 2400);
DOT 1 (-1050 2250);
FORCENOTE
PVDDQ (SINGLE SIDE) CAP: 10UF X1, 22UF X50
(-2800 5200) 0;
DISPLAY LEFT (-2800 5200);
DISPLAY 1.021277 (-2800 5200);
PAINT PURPLE (-2800 5200);
FORCENOTE
PVDDQ (DOUBLE SIDE) CAP: 100UF X8, 47UF X41
(-2800 5150) 0;
DISPLAY LEFT (-2800 5150);
DISPLAY 1.021277 (-2800 5150);
PAINT PURPLE (-2800 5150);
FORCENOTE
PVTT CAP: 100UF X2, 47UF X1
(-2800 5250) 0;
DISPLAY LEFT (-2800 5250);
DISPLAY 1.021277 (-2800 5250);
PAINT PURPLE (-2800 5250);
FORCENOTE
PLACE CAP NEAR DIMM CONNECTOR
(-5288 1052) 0;
DISPLAY LEFT (-5288 1052);
DISPLAY 1.957447 (-5288 1052);
PAINT PURPLE (-5288 1052);
FORCENOTE
SMBUS ADDR: 0XA8
(-5250 900) 0;
DISPLAY LEFT (-5250 900);
DISPLAY 1.957447 (-5250 900);
PAINT PURPLE (-5250 900);
FORCENOTE
PVPP CAP: 10UF X12
(-2800 5300) 0;
DISPLAY LEFT (-2800 5300);
DISPLAY 1.021277 (-2800 5300);
PAINT PURPLE (-2800 5300);
FORCENOTE
CAP BETWEEN DIMM
(-2800 5375) 0;
DISPLAY LEFT (-2800 5375);
DISPLAY 1.276596 (-2800 5375);
PAINT PURPLE (-2800 5375);
QUIT
